FILE_TYPE = MACRO_DRAWING;
SET COLOR_WIRE YELLOW;
SET COLOR_PROP MONO;
SET COLOR_DOT WHITE;
SET COLOR_ARC YELLOW;
SET COLOR_BODY GREEN;
SET COLOR_NOTE MONO;
SET PROP_DISPLAY VALUE;
SET PAGE_NUMBER P76;
FORCEADD CAP_A..1
(-1275 4450);
FORCEPROP 1 LAST LOCATION C3D21
J 0
(-1225 4550);
DISPLAY 0.617021 (-1225 4550);
PAINT AQUA (-1225 4550);
FORCEPROP 1 LAST PART_NUMBER E15431-004
J 0
(-1225 4300);
DISPLAY 0.617021 (-1225 4300);
PAINT BLUE (-1225 4300);
FORCEPROP 1 LAST VALUE 22.0UF
J 0
(-1225 4500);
DISPLAY 0.617021 (-1225 4500);
PAINT SKYBLUE (-1225 4500);
FORCEPROP 1 LAST TOLERANCE 20%
J 0
(-1225 4400);
DISPLAY 0.617021 (-1225 4400);
PAINT SKYBLUE (-1225 4400);
FORCEPROP 1 LAST PACK_TYPE 0603V
J 0
(-1225 4250);
DISPLAY 0.617021 (-1225 4250);
PAINT SKYBLUE (-1225 4250);
FORCEPROP 1 LAST VOLTAGE 4V
J 0
(-1225 4450);
DISPLAY 0.617021 (-1225 4450);
PAINT SKYBLUE (-1225 4450);
FORCEPROP 1 LAST MATERIAL X6S
J 0
(-1225 4350);
DISPLAY 0.617021 (-1225 4350);
PAINT SKYBLUE (-1225 4350);
FORCEPROP 1 LASTPIN (-1275 4550) $PN 1
J 0
(-1265 4530);
DISPLAY 0.617021 (-1265 4530);
PAINT GREEN (-1265 4530);
FORCEPROP 1 LASTPIN (-1275 4350) $PN 2
J 0
(-1265 4330);
DISPLAY 0.617021 (-1265 4330);
PAINT GREEN (-1265 4330);
FORCEPROP 2 LAST CDS_LOCATION C3D21
J 0
(-1225 4550);
DISPLAY 0.617021 (-1225 4550);
PAINT AQUA (-1225 4550);
DISPLAY INVISIBLE (-1225 4550);
FORCEPROP 2 LAST BOM_COST PROC
J 0
(-1275 4450);
PAINT MONO (-1275 4450);
DISPLAY INVISIBLE (-1275 4450);
FORCEPROP 2 LAST CDS_LIB dev_discrete
J 0
(-1275 4450);
PAINT ORANGE (-1275 4450);
DISPLAY INVISIBLE (-1275 4450);
FORCEPROP 2 LAST CDS_SEC 1
J 0
(-1225 4650);
PAINT MONO (-1225 4650);
DISPLAY INVISIBLE (-1225 4650);
FORCEPROP 2 LAST $SEC 1
J 0
(-1225 4650);
PAINT MONO (-1225 4650);
DISPLAY INVISIBLE (-1225 4650);
FORCEPROP 1 LAST PATH I1
J 0
(-1225 4600);
DISPLAY 0.978723 (-1225 4600);
PAINT WHITE (-1225 4600);
DISPLAY INVISIBLE (-1225 4600);
FORCEPROP 2 LAST ROOM PVCCIN_CPU1_DECAP_VR
J 0
(-1225 4550);
PAINT ORANGE (-1225 4550);
DISPLAY INVISIBLE (-1225 4550);
FORCEADD CAP_A..1
(-3250 4425);
FORCEPROP 1 LAST LOCATION C2D40
J 0
(-3200 4525);
DISPLAY 0.617021 (-3200 4525);
PAINT AQUA (-3200 4525);
FORCEPROP 1 LAST PART_NUMBER E15431-004
J 0
(-3200 4275);
DISPLAY 0.617021 (-3200 4275);
PAINT BLUE (-3200 4275);
FORCEPROP 1 LAST VALUE 22.0UF
J 0
(-3200 4475);
DISPLAY 0.617021 (-3200 4475);
PAINT SKYBLUE (-3200 4475);
FORCEPROP 1 LAST TOLERANCE 20%
J 0
(-3200 4375);
DISPLAY 0.617021 (-3200 4375);
PAINT SKYBLUE (-3200 4375);
FORCEPROP 1 LAST PACK_TYPE 0603V
J 0
(-3200 4225);
DISPLAY 0.617021 (-3200 4225);
PAINT SKYBLUE (-3200 4225);
FORCEPROP 1 LAST VOLTAGE 4V
J 0
(-3200 4425);
DISPLAY 0.617021 (-3200 4425);
PAINT SKYBLUE (-3200 4425);
FORCEPROP 1 LAST MATERIAL X6S
J 0
(-3200 4325);
DISPLAY 0.617021 (-3200 4325);
PAINT SKYBLUE (-3200 4325);
FORCEPROP 1 LASTPIN (-3250 4525) $PN 1
J 0
(-3240 4505);
DISPLAY 0.617021 (-3240 4505);
PAINT GREEN (-3240 4505);
FORCEPROP 1 LASTPIN (-3250 4325) $PN 2
J 0
(-3240 4305);
DISPLAY 0.617021 (-3240 4305);
PAINT GREEN (-3240 4305);
FORCEPROP 2 LAST CDS_LOCATION C2D40
J 0
(-3200 4525);
DISPLAY 0.617021 (-3200 4525);
PAINT AQUA (-3200 4525);
DISPLAY INVISIBLE (-3200 4525);
FORCEPROP 2 LAST BOM_COST PROC
J 0
(-3250 4425);
PAINT MONO (-3250 4425);
DISPLAY INVISIBLE (-3250 4425);
FORCEPROP 2 LAST CDS_LIB dev_discrete
J 0
(-3250 4425);
PAINT ORANGE (-3250 4425);
DISPLAY INVISIBLE (-3250 4425);
FORCEPROP 2 LAST CDS_SEC 1
J 0
(-3200 4625);
PAINT MONO (-3200 4625);
DISPLAY INVISIBLE (-3200 4625);
FORCEPROP 2 LAST $SEC 1
J 0
(-3200 4625);
PAINT MONO (-3200 4625);
DISPLAY INVISIBLE (-3200 4625);
FORCEPROP 1 LAST PATH I10
J 0
(-3200 4575);
DISPLAY 0.978723 (-3200 4575);
PAINT WHITE (-3200 4575);
DISPLAY INVISIBLE (-3200 4575);
FORCEPROP 2 LAST ROOM PVCCIN_CPU1_DECAP_VR
J 0
(-3200 4525);
PAINT ORANGE (-3200 4525);
DISPLAY INVISIBLE (-3200 4525);
FORCEADD CAP..1
(-5300 1550);
FORCEPROP 1 LAST LOCATION C7P2
J 0
(-5250 1650);
DISPLAY 0.617021 (-5250 1650);
PAINT AQUA (-5250 1650);
FORCEPROP 1 LAST PART_NUMBER C95333-006
R 1
J 0
(-5350 1375);
DISPLAY 0.617021 (-5350 1375);
PAINT BLUE (-5350 1375);
FORCEPROP 1 LAST VALUE 47UF
J 0
(-5250 1600);
DISPLAY 0.617021 (-5250 1600);
PAINT SKYBLUE (-5250 1600);
FORCEPROP 1 LAST TOLERANCE 20%
J 0
(-5250 1500);
DISPLAY 0.617021 (-5250 1500);
PAINT SKYBLUE (-5250 1500);
FORCEPROP 1 LAST PACK_TYPE 0805
J 0
(-5250 1400);
DISPLAY 0.617021 (-5250 1400);
PAINT SKYBLUE (-5250 1400);
FORCEPROP 1 LASTPIN (-5300 1450) $PN 2
J 0
(-5290 1430);
DISPLAY 0.617021 (-5290 1430);
PAINT GREEN (-5290 1430);
FORCEPROP 1 LASTPIN (-5300 1650) $PN 1
J 0
(-5290 1630);
DISPLAY 0.617021 (-5290 1630);
PAINT GREEN (-5290 1630);
FORCEPROP 1 LAST VOLTAGE 4V
J 0
(-5250 1550);
PAINT SKYBLUE (-5250 1550);
DISPLAY INVISIBLE (-5250 1550);
FORCEPROP 1 LAST MATERIAL X6S
J 0
(-5250 1450);
PAINT SKYBLUE (-5250 1450);
DISPLAY INVISIBLE (-5250 1450);
FORCEPROP 2 LAST CDS_LIB mstr_discrete
J 0
(-5300 1550);
PAINT ORANGE (-5300 1550);
DISPLAY INVISIBLE (-5300 1550);
FORCEPROP 2 LAST BOM_COST PROC
J 0
(-5300 1550);
PAINT MONO (-5300 1550);
DISPLAY INVISIBLE (-5300 1550);
FORCEPROP 2 LAST CDS_SEC 1
J 0
(-5250 1750);
DISPLAY 1.021277 (-5250 1750);
PAINT ORANGE (-5250 1750);
DISPLAY INVISIBLE (-5250 1750);
FORCEPROP 2 LAST $SEC 1
J 0
(-5250 1750);
DISPLAY 0.680851 (-5250 1750);
PAINT MONO (-5250 1750);
DISPLAY INVISIBLE (-5250 1750);
FORCEPROP 2 LAST CDS_LOCATION C7P2
J 0
(-5250 1650);
DISPLAY 0.617021 (-5250 1650);
PAINT AQUA (-5250 1650);
DISPLAY INVISIBLE (-5250 1650);
FORCEPROP 1 LAST PATH I100
J 0
(-5250 1700);
DISPLAY 0.978723 (-5250 1700);
PAINT WHITE (-5250 1700);
DISPLAY INVISIBLE (-5250 1700);
FORCEPROP 2 LAST ROOM PVCCIN_CPU1_DECAP_VR
J 0
(-5250 1650);
PAINT ORANGE (-5250 1650);
DISPLAY INVISIBLE (-5250 1650);
FORCEADD CAP..1
(-5625 1550);
FORCEPROP 1 LAST LOCATION C8P3
J 0
(-5575 1650);
DISPLAY 0.617021 (-5575 1650);
PAINT AQUA (-5575 1650);
FORCEPROP 1 LAST PART_NUMBER C95333-006
R 1
J 0
(-5675 1375);
DISPLAY 0.617021 (-5675 1375);
PAINT BLUE (-5675 1375);
FORCEPROP 1 LAST VALUE 47UF
J 0
(-5575 1600);
DISPLAY 0.617021 (-5575 1600);
PAINT SKYBLUE (-5575 1600);
FORCEPROP 1 LAST TOLERANCE 20%
J 0
(-5575 1500);
DISPLAY 0.617021 (-5575 1500);
PAINT SKYBLUE (-5575 1500);
FORCEPROP 1 LAST PACK_TYPE 0805
J 0
(-5575 1400);
DISPLAY 0.617021 (-5575 1400);
PAINT SKYBLUE (-5575 1400);
FORCEPROP 1 LASTPIN (-5625 1450) $PN 2
J 0
(-5615 1430);
DISPLAY 0.617021 (-5615 1430);
PAINT GREEN (-5615 1430);
FORCEPROP 1 LASTPIN (-5625 1650) $PN 1
J 0
(-5615 1630);
DISPLAY 0.617021 (-5615 1630);
PAINT GREEN (-5615 1630);
FORCEPROP 1 LAST VOLTAGE 4V
J 0
(-5575 1550);
PAINT SKYBLUE (-5575 1550);
DISPLAY INVISIBLE (-5575 1550);
FORCEPROP 1 LAST MATERIAL X6S
J 0
(-5575 1450);
PAINT SKYBLUE (-5575 1450);
DISPLAY INVISIBLE (-5575 1450);
FORCEPROP 2 LAST CDS_LIB mstr_discrete
J 0
(-5625 1550);
PAINT ORANGE (-5625 1550);
DISPLAY INVISIBLE (-5625 1550);
FORCEPROP 2 LAST BOM_COST PROC
J 0
(-5625 1550);
PAINT MONO (-5625 1550);
DISPLAY INVISIBLE (-5625 1550);
FORCEPROP 2 LAST CDS_SEC 1
J 0
(-5575 1750);
DISPLAY 1.021277 (-5575 1750);
PAINT ORANGE (-5575 1750);
DISPLAY INVISIBLE (-5575 1750);
FORCEPROP 2 LAST $SEC 1
J 0
(-5575 1750);
DISPLAY 0.680851 (-5575 1750);
PAINT MONO (-5575 1750);
DISPLAY INVISIBLE (-5575 1750);
FORCEPROP 2 LAST CDS_LOCATION C8P3
J 0
(-5575 1650);
DISPLAY 0.617021 (-5575 1650);
PAINT AQUA (-5575 1650);
DISPLAY INVISIBLE (-5575 1650);
FORCEPROP 1 LAST PATH I101
J 0
(-5575 1700);
DISPLAY 0.978723 (-5575 1700);
PAINT WHITE (-5575 1700);
DISPLAY INVISIBLE (-5575 1700);
FORCEPROP 2 LAST ROOM PVCCIN_CPU1_DECAP_VR
J 0
(-5550 1650);
PAINT ORANGE (-5550 1650);
DISPLAY INVISIBLE (-5550 1650);
FORCEADD CAP..1
(-5975 1550);
FORCEPROP 1 LAST LOCATION C8P19
J 0
(-5925 1650);
DISPLAY 0.617021 (-5925 1650);
PAINT AQUA (-5925 1650);
FORCEPROP 1 LAST PART_NUMBER C95333-006
R 1
J 0
(-6025 1375);
DISPLAY 0.617021 (-6025 1375);
PAINT BLUE (-6025 1375);
FORCEPROP 1 LAST VALUE 47UF
J 0
(-5925 1600);
DISPLAY 0.617021 (-5925 1600);
PAINT SKYBLUE (-5925 1600);
FORCEPROP 1 LAST TOLERANCE 20%
J 0
(-5925 1500);
DISPLAY 0.617021 (-5925 1500);
PAINT SKYBLUE (-5925 1500);
FORCEPROP 1 LAST PACK_TYPE 0805
J 0
(-5925 1400);
DISPLAY 0.617021 (-5925 1400);
PAINT SKYBLUE (-5925 1400);
FORCEPROP 1 LASTPIN (-5975 1450) $PN 2
J 0
(-5965 1430);
DISPLAY 0.617021 (-5965 1430);
PAINT GREEN (-5965 1430);
FORCEPROP 1 LASTPIN (-5975 1650) $PN 1
J 0
(-5965 1630);
DISPLAY 0.617021 (-5965 1630);
PAINT GREEN (-5965 1630);
FORCEPROP 1 LAST VOLTAGE 4V
J 0
(-5925 1550);
PAINT SKYBLUE (-5925 1550);
DISPLAY INVISIBLE (-5925 1550);
FORCEPROP 1 LAST MATERIAL X6S
J 0
(-5925 1450);
PAINT SKYBLUE (-5925 1450);
DISPLAY INVISIBLE (-5925 1450);
FORCEPROP 2 LAST CDS_LIB mstr_discrete
J 0
(-5975 1550);
PAINT ORANGE (-5975 1550);
DISPLAY INVISIBLE (-5975 1550);
FORCEPROP 2 LAST BOM_COST PROC
J 0
(-5975 1550);
PAINT MONO (-5975 1550);
DISPLAY INVISIBLE (-5975 1550);
FORCEPROP 2 LAST CDS_SEC 1
J 0
(-5925 1750);
DISPLAY 1.021277 (-5925 1750);
PAINT ORANGE (-5925 1750);
DISPLAY INVISIBLE (-5925 1750);
FORCEPROP 2 LAST $SEC 1
J 0
(-5925 1750);
DISPLAY 0.680851 (-5925 1750);
PAINT MONO (-5925 1750);
DISPLAY INVISIBLE (-5925 1750);
FORCEPROP 2 LAST CDS_LOCATION C8P19
J 0
(-5925 1650);
DISPLAY 0.617021 (-5925 1650);
PAINT AQUA (-5925 1650);
DISPLAY INVISIBLE (-5925 1650);
FORCEPROP 1 LAST PATH I103
J 0
(-5925 1700);
DISPLAY 0.978723 (-5925 1700);
PAINT WHITE (-5925 1700);
DISPLAY INVISIBLE (-5925 1700);
FORCEPROP 2 LAST ROOM PVCCIN_CPU1_DECAP_VR
J 0
(-5925 1650);
PAINT ORANGE (-5925 1650);
DISPLAY INVISIBLE (-5925 1650);
FORCEADD CAP..1
(-5275 875);
FORCEPROP 1 LAST LOCATION C7P1
J 0
(-5225 975);
DISPLAY 0.617021 (-5225 975);
PAINT AQUA (-5225 975);
FORCEPROP 1 LAST PART_NUMBER C95333-006
R 1
J 0
(-5325 700);
DISPLAY 0.617021 (-5325 700);
PAINT BLUE (-5325 700);
FORCEPROP 1 LAST VALUE 47UF
J 0
(-5225 925);
DISPLAY 0.617021 (-5225 925);
PAINT SKYBLUE (-5225 925);
FORCEPROP 1 LAST TOLERANCE 20%
J 0
(-5225 825);
DISPLAY 0.617021 (-5225 825);
PAINT SKYBLUE (-5225 825);
FORCEPROP 1 LAST PACK_TYPE 0805
J 0
(-5225 725);
DISPLAY 0.617021 (-5225 725);
PAINT SKYBLUE (-5225 725);
FORCEPROP 1 LASTPIN (-5275 775) $PN 2
J 0
(-5265 755);
DISPLAY 0.617021 (-5265 755);
PAINT GREEN (-5265 755);
FORCEPROP 1 LASTPIN (-5275 975) $PN 1
J 0
(-5265 955);
DISPLAY 0.617021 (-5265 955);
PAINT GREEN (-5265 955);
FORCEPROP 1 LAST VOLTAGE 4V
J 0
(-5225 875);
PAINT SKYBLUE (-5225 875);
DISPLAY INVISIBLE (-5225 875);
FORCEPROP 1 LAST MATERIAL X6S
J 0
(-5225 775);
PAINT SKYBLUE (-5225 775);
DISPLAY INVISIBLE (-5225 775);
FORCEPROP 2 LAST BOM_COST PROC
J 0
(-5275 875);
PAINT MONO (-5275 875);
DISPLAY INVISIBLE (-5275 875);
FORCEPROP 2 LAST CDS_LIB mstr_discrete
J 0
(-5275 875);
PAINT ORANGE (-5275 875);
DISPLAY INVISIBLE (-5275 875);
FORCEPROP 2 LAST CDS_SEC 1
J 0
(-5225 1075);
DISPLAY 1.021277 (-5225 1075);
PAINT ORANGE (-5225 1075);
DISPLAY INVISIBLE (-5225 1075);
FORCEPROP 2 LAST $SEC 1
J 0
(-5225 1075);
DISPLAY 0.680851 (-5225 1075);
PAINT MONO (-5225 1075);
DISPLAY INVISIBLE (-5225 1075);
FORCEPROP 2 LAST CDS_LOCATION C7P1
J 0
(-5225 975);
DISPLAY 0.617021 (-5225 975);
PAINT AQUA (-5225 975);
DISPLAY INVISIBLE (-5225 975);
FORCEPROP 1 LAST PATH I105
J 0
(-5225 1025);
DISPLAY 0.978723 (-5225 1025);
PAINT WHITE (-5225 1025);
DISPLAY INVISIBLE (-5225 1025);
FORCEPROP 2 LAST ROOM PVCCIN_CPU1_DECAP_VR
J 0
(-5225 975);
PAINT ORANGE (-5225 975);
DISPLAY INVISIBLE (-5225 975);
FORCEADD CAP..1
(-5600 875);
FORCEPROP 1 LAST LOCATION C8P34
J 0
(-5550 975);
DISPLAY 0.617021 (-5550 975);
PAINT AQUA (-5550 975);
FORCEPROP 1 LAST PART_NUMBER C95333-006
R 1
J 0
(-5650 700);
DISPLAY 0.617021 (-5650 700);
PAINT BLUE (-5650 700);
FORCEPROP 1 LAST VALUE 47UF
J 0
(-5550 925);
DISPLAY 0.617021 (-5550 925);
PAINT SKYBLUE (-5550 925);
FORCEPROP 1 LAST TOLERANCE 20%
J 0
(-5550 825);
DISPLAY 0.617021 (-5550 825);
PAINT SKYBLUE (-5550 825);
FORCEPROP 1 LAST PACK_TYPE 0805
J 0
(-5550 725);
DISPLAY 0.617021 (-5550 725);
PAINT SKYBLUE (-5550 725);
FORCEPROP 1 LASTPIN (-5600 775) $PN 2
J 0
(-5590 755);
DISPLAY 0.617021 (-5590 755);
PAINT GREEN (-5590 755);
FORCEPROP 1 LASTPIN (-5600 975) $PN 1
J 0
(-5590 955);
DISPLAY 0.617021 (-5590 955);
PAINT GREEN (-5590 955);
FORCEPROP 1 LAST VOLTAGE 4V
J 0
(-5550 875);
PAINT SKYBLUE (-5550 875);
DISPLAY INVISIBLE (-5550 875);
FORCEPROP 1 LAST MATERIAL X6S
J 0
(-5550 775);
PAINT SKYBLUE (-5550 775);
DISPLAY INVISIBLE (-5550 775);
FORCEPROP 2 LAST BOM_COST PROC
J 0
(-5600 875);
PAINT MONO (-5600 875);
DISPLAY INVISIBLE (-5600 875);
FORCEPROP 2 LAST CDS_LIB mstr_discrete
J 0
(-5600 875);
PAINT ORANGE (-5600 875);
DISPLAY INVISIBLE (-5600 875);
FORCEPROP 2 LAST CDS_SEC 1
J 0
(-5550 1075);
DISPLAY 1.021277 (-5550 1075);
PAINT ORANGE (-5550 1075);
DISPLAY INVISIBLE (-5550 1075);
FORCEPROP 2 LAST $SEC 1
J 0
(-5550 1075);
DISPLAY 0.680851 (-5550 1075);
PAINT MONO (-5550 1075);
DISPLAY INVISIBLE (-5550 1075);
FORCEPROP 2 LAST CDS_LOCATION C8P34
J 0
(-5550 975);
DISPLAY 0.617021 (-5550 975);
PAINT AQUA (-5550 975);
DISPLAY INVISIBLE (-5550 975);
FORCEPROP 1 LAST PATH I106
J 0
(-5550 1025);
DISPLAY 0.978723 (-5550 1025);
PAINT WHITE (-5550 1025);
DISPLAY INVISIBLE (-5550 1025);
FORCEPROP 2 LAST ROOM PVCCIN_CPU1_DECAP_VR
J 0
(-5525 975);
PAINT ORANGE (-5525 975);
DISPLAY INVISIBLE (-5525 975);
FORCEADD CAP..1
(-5950 875);
FORCEPROP 1 LAST LOCATION C8P12
J 0
(-5900 975);
DISPLAY 0.617021 (-5900 975);
PAINT AQUA (-5900 975);
FORCEPROP 1 LAST PART_NUMBER C95333-006
R 1
J 0
(-6000 700);
DISPLAY 0.617021 (-6000 700);
PAINT BLUE (-6000 700);
FORCEPROP 1 LAST VALUE 47UF
J 0
(-5900 925);
DISPLAY 0.617021 (-5900 925);
PAINT SKYBLUE (-5900 925);
FORCEPROP 1 LAST TOLERANCE 20%
J 0
(-5900 825);
DISPLAY 0.617021 (-5900 825);
PAINT SKYBLUE (-5900 825);
FORCEPROP 1 LAST PACK_TYPE 0805
J 0
(-5900 725);
DISPLAY 0.617021 (-5900 725);
PAINT SKYBLUE (-5900 725);
FORCEPROP 1 LASTPIN (-5950 775) $PN 2
J 0
(-5940 755);
DISPLAY 0.617021 (-5940 755);
PAINT GREEN (-5940 755);
FORCEPROP 1 LASTPIN (-5950 975) $PN 1
J 0
(-5940 955);
DISPLAY 0.617021 (-5940 955);
PAINT GREEN (-5940 955);
FORCEPROP 1 LAST VOLTAGE 4V
J 0
(-5900 875);
PAINT SKYBLUE (-5900 875);
DISPLAY INVISIBLE (-5900 875);
FORCEPROP 1 LAST MATERIAL X6S
J 0
(-5900 775);
PAINT SKYBLUE (-5900 775);
DISPLAY INVISIBLE (-5900 775);
FORCEPROP 2 LAST BOM_COST PROC
J 0
(-5950 875);
PAINT MONO (-5950 875);
DISPLAY INVISIBLE (-5950 875);
FORCEPROP 2 LAST CDS_LIB mstr_discrete
J 0
(-5950 875);
PAINT ORANGE (-5950 875);
DISPLAY INVISIBLE (-5950 875);
FORCEPROP 2 LAST CDS_SEC 1
J 0
(-5900 1075);
DISPLAY 1.021277 (-5900 1075);
PAINT ORANGE (-5900 1075);
DISPLAY INVISIBLE (-5900 1075);
FORCEPROP 2 LAST $SEC 1
J 0
(-5900 1075);
DISPLAY 0.680851 (-5900 1075);
PAINT MONO (-5900 1075);
DISPLAY INVISIBLE (-5900 1075);
FORCEPROP 2 LAST CDS_LOCATION C8P12
J 0
(-5900 975);
DISPLAY 0.617021 (-5900 975);
PAINT AQUA (-5900 975);
DISPLAY INVISIBLE (-5900 975);
FORCEPROP 1 LAST PATH I107
J 0
(-5900 1025);
DISPLAY 0.978723 (-5900 1025);
PAINT WHITE (-5900 1025);
DISPLAY INVISIBLE (-5900 1025);
FORCEPROP 2 LAST ROOM PVCCIN_CPU1_DECAP_VR
J 0
(-5900 975);
PAINT ORANGE (-5900 975);
DISPLAY INVISIBLE (-5900 975);
FORCEADD CAP_A..1
(-6300 3775);
FORCEPROP 1 LAST LOCATION C2D26
J 0
(-6250 3875);
DISPLAY 0.617021 (-6250 3875);
PAINT AQUA (-6250 3875);
FORCEPROP 1 LAST PART_NUMBER E15431-004
J 0
(-6250 3625);
DISPLAY 0.617021 (-6250 3625);
PAINT BLUE (-6250 3625);
FORCEPROP 1 LAST VALUE 22.0UF
J 0
(-6250 3825);
DISPLAY 0.617021 (-6250 3825);
PAINT SKYBLUE (-6250 3825);
FORCEPROP 1 LAST TOLERANCE 20%
J 0
(-6250 3725);
DISPLAY 0.617021 (-6250 3725);
PAINT SKYBLUE (-6250 3725);
FORCEPROP 1 LAST PACK_TYPE 0603V
J 0
(-6250 3575);
DISPLAY 0.617021 (-6250 3575);
PAINT SKYBLUE (-6250 3575);
FORCEPROP 1 LAST VOLTAGE 4V
J 0
(-6250 3775);
DISPLAY 0.617021 (-6250 3775);
PAINT SKYBLUE (-6250 3775);
FORCEPROP 1 LAST MATERIAL X6S
J 0
(-6250 3675);
DISPLAY 0.617021 (-6250 3675);
PAINT SKYBLUE (-6250 3675);
FORCEPROP 1 LASTPIN (-6300 3875) $PN 1
J 0
(-6290 3855);
DISPLAY 0.617021 (-6290 3855);
PAINT GREEN (-6290 3855);
FORCEPROP 1 LASTPIN (-6300 3675) $PN 2
J 0
(-6290 3655);
DISPLAY 0.617021 (-6290 3655);
PAINT GREEN (-6290 3655);
FORCEPROP 2 LAST CDS_LOCATION C2D26
J 0
(-6250 3875);
DISPLAY 0.617021 (-6250 3875);
PAINT AQUA (-6250 3875);
DISPLAY INVISIBLE (-6250 3875);
FORCEPROP 2 LAST BOM_COST PROC
J 0
(-6300 3775);
PAINT MONO (-6300 3775);
DISPLAY INVISIBLE (-6300 3775);
FORCEPROP 2 LAST CDS_LIB dev_discrete
J 0
(-6300 3775);
PAINT ORANGE (-6300 3775);
DISPLAY INVISIBLE (-6300 3775);
FORCEPROP 2 LAST CDS_SEC 1
J 0
(-6250 3975);
PAINT MONO (-6250 3975);
DISPLAY INVISIBLE (-6250 3975);
FORCEPROP 2 LAST $SEC 1
J 0
(-6250 3975);
PAINT MONO (-6250 3975);
DISPLAY INVISIBLE (-6250 3975);
FORCEPROP 1 LAST PATH I108
J 0
(-6250 3925);
DISPLAY 0.978723 (-6250 3925);
PAINT WHITE (-6250 3925);
DISPLAY INVISIBLE (-6250 3925);
FORCEPROP 2 LAST ROOM PVCCIN_CPU1_DECAP_VR
J 0
(-6250 3875);
PAINT ORANGE (-6250 3875);
DISPLAY INVISIBLE (-6250 3875);
FORCEADD GND..1
(-6300 3450);
FORCEPROP 3 LASTPIN (-6300 3500) SIG_NAME GND\g
J 0
(-6290 3510);
DISPLAY 0.659574 (-6290 3510);
PAINT MONO (-6290 3510);
DISPLAY INVISIBLE (-6290 3510);
FORCEPROP 1 LAST VOLTAGE 0
J 0
(-6300 3450);
PAINT SKYBLUE (-6300 3450);
DISPLAY INVISIBLE (-6300 3450);
FORCEPROP 2 LAST CDS_LIB mstr_symbols
J 0
(-6300 3450);
PAINT ORANGE (-6300 3450);
DISPLAY INVISIBLE (-6300 3450);
FORCEPROP 1 LAST SIZE 1B
J 0
(-6225 3400);
DISPLAY 0.893617 (-6225 3400);
PAINT GREEN (-6225 3400);
DISPLAY INVISIBLE (-6225 3400);
FORCEPROP 1 LAST BODY_TYPE PLUMBING
J 0
(-6345 3407);
DISPLAY 0.340426 (-6345 3407);
PAINT GREEN (-6345 3407);
DISPLAY INVISIBLE (-6345 3407);
FORCEPROP 1 LAST PATH I109
J 0
(-6225 3450);
DISPLAY 0.872340 (-6225 3450);
PAINT AQUA (-6225 3450);
DISPLAY INVISIBLE (-6225 3450);
FORCEPROP 2 LAST ROOM PVCCIN_CPU1_DECAP_VR
J 0
(-6850 3525);
PAINT ORANGE (-6850 3525);
DISPLAY INVISIBLE (-6850 3525);
FORCEPROP 1 LAST HDL_POWER GND
J 0
(-6300 3600);
DISPLAY 0.893617 (-6300 3600);
PAINT GREEN (-6300 3600);
DISPLAY INVISIBLE (-6300 3600);
FORCEADD CAP_A..1
(-7000 3775);
FORCEPROP 1 LAST LOCATION C3D1
J 0
(-6950 3875);
DISPLAY 0.617021 (-6950 3875);
PAINT AQUA (-6950 3875);
FORCEPROP 1 LAST PART_NUMBER E15431-004
J 0
(-6950 3625);
DISPLAY 0.617021 (-6950 3625);
PAINT BLUE (-6950 3625);
FORCEPROP 1 LAST VALUE 22.0UF
J 0
(-6950 3825);
DISPLAY 0.617021 (-6950 3825);
PAINT SKYBLUE (-6950 3825);
FORCEPROP 1 LAST TOLERANCE 20%
J 0
(-6950 3725);
DISPLAY 0.617021 (-6950 3725);
PAINT SKYBLUE (-6950 3725);
FORCEPROP 1 LAST PACK_TYPE 0603V
J 0
(-6950 3575);
DISPLAY 0.617021 (-6950 3575);
PAINT SKYBLUE (-6950 3575);
FORCEPROP 1 LAST VOLTAGE 4V
J 0
(-6950 3775);
DISPLAY 0.617021 (-6950 3775);
PAINT SKYBLUE (-6950 3775);
FORCEPROP 1 LAST MATERIAL X6S
J 0
(-6950 3675);
DISPLAY 0.617021 (-6950 3675);
PAINT SKYBLUE (-6950 3675);
FORCEPROP 1 LASTPIN (-7000 3875) $PN 1
J 0
(-6990 3855);
DISPLAY 0.617021 (-6990 3855);
PAINT GREEN (-6990 3855);
FORCEPROP 1 LASTPIN (-7000 3675) $PN 2
J 0
(-6990 3655);
DISPLAY 0.617021 (-6990 3655);
PAINT GREEN (-6990 3655);
FORCEPROP 2 LAST CDS_LOCATION C3D1
J 0
(-6950 3875);
DISPLAY 0.617021 (-6950 3875);
PAINT AQUA (-6950 3875);
DISPLAY INVISIBLE (-6950 3875);
FORCEPROP 2 LAST BOM_COST PROC
J 0
(-7000 3775);
PAINT MONO (-7000 3775);
DISPLAY INVISIBLE (-7000 3775);
FORCEPROP 2 LAST CDS_LIB dev_discrete
J 0
(-7000 3775);
PAINT ORANGE (-7000 3775);
DISPLAY INVISIBLE (-7000 3775);
FORCEPROP 2 LAST CDS_SEC 1
J 0
(-6950 3975);
PAINT MONO (-6950 3975);
DISPLAY INVISIBLE (-6950 3975);
FORCEPROP 2 LAST $SEC 1
J 0
(-6950 3975);
PAINT MONO (-6950 3975);
DISPLAY INVISIBLE (-6950 3975);
FORCEPROP 1 LAST PATH I111
J 0
(-6950 3925);
DISPLAY 0.978723 (-6950 3925);
PAINT WHITE (-6950 3925);
DISPLAY INVISIBLE (-6950 3925);
FORCEPROP 2 LAST ROOM PVCCIN_CPU1_DECAP_VR
J 0
(-6950 3875);
PAINT ORANGE (-6950 3875);
DISPLAY INVISIBLE (-6950 3875);
FORCEADD CAP_A..1
(-6250 3150);
FORCEPROP 1 LAST LOCATION C2D23
J 0
(-6200 3250);
DISPLAY 0.617021 (-6200 3250);
PAINT AQUA (-6200 3250);
FORCEPROP 1 LAST PART_NUMBER E15431-004
J 0
(-6200 3000);
DISPLAY 0.617021 (-6200 3000);
PAINT BLUE (-6200 3000);
FORCEPROP 1 LAST VALUE 22.0UF
J 0
(-6200 3200);
DISPLAY 0.617021 (-6200 3200);
PAINT SKYBLUE (-6200 3200);
FORCEPROP 1 LAST TOLERANCE 20%
J 0
(-6200 3100);
DISPLAY 0.617021 (-6200 3100);
PAINT SKYBLUE (-6200 3100);
FORCEPROP 1 LAST PACK_TYPE 0603V
J 0
(-6200 2950);
DISPLAY 0.617021 (-6200 2950);
PAINT SKYBLUE (-6200 2950);
FORCEPROP 1 LAST VOLTAGE 4V
J 0
(-6200 3150);
DISPLAY 0.617021 (-6200 3150);
PAINT SKYBLUE (-6200 3150);
FORCEPROP 1 LAST MATERIAL X6S
J 0
(-6200 3050);
DISPLAY 0.617021 (-6200 3050);
PAINT SKYBLUE (-6200 3050);
FORCEPROP 1 LASTPIN (-6250 3250) $PN 1
J 0
(-6240 3230);
DISPLAY 0.617021 (-6240 3230);
PAINT GREEN (-6240 3230);
FORCEPROP 1 LASTPIN (-6250 3050) $PN 2
J 0
(-6240 3030);
DISPLAY 0.617021 (-6240 3030);
PAINT GREEN (-6240 3030);
FORCEPROP 2 LAST CDS_LOCATION C2D23
J 0
(-6200 3250);
DISPLAY 0.617021 (-6200 3250);
PAINT AQUA (-6200 3250);
DISPLAY INVISIBLE (-6200 3250);
FORCEPROP 2 LAST BOM_COST PROC
J 0
(-6250 3150);
PAINT MONO (-6250 3150);
DISPLAY INVISIBLE (-6250 3150);
FORCEPROP 2 LAST CDS_LIB dev_discrete
J 0
(-6250 3150);
PAINT ORANGE (-6250 3150);
DISPLAY INVISIBLE (-6250 3150);
FORCEPROP 2 LAST CDS_SEC 1
J 0
(-6200 3350);
PAINT MONO (-6200 3350);
DISPLAY INVISIBLE (-6200 3350);
FORCEPROP 2 LAST $SEC 1
J 0
(-6200 3350);
PAINT MONO (-6200 3350);
DISPLAY INVISIBLE (-6200 3350);
FORCEPROP 1 LAST PATH I112
J 0
(-6200 3300);
DISPLAY 0.978723 (-6200 3300);
PAINT WHITE (-6200 3300);
DISPLAY INVISIBLE (-6200 3300);
FORCEPROP 2 LAST ROOM PVCCIN_CPU1_DECAP_VR
J 0
(-6200 3250);
PAINT ORANGE (-6200 3250);
DISPLAY INVISIBLE (-6200 3250);
FORCEADD GND..1
(-6250 2825);
FORCEPROP 3 LASTPIN (-6250 2875) SIG_NAME GND\g
J 0
(-6240 2885);
DISPLAY 0.659574 (-6240 2885);
PAINT MONO (-6240 2885);
DISPLAY INVISIBLE (-6240 2885);
FORCEPROP 1 LAST VOLTAGE 0
J 0
(-6250 2825);
PAINT SKYBLUE (-6250 2825);
DISPLAY INVISIBLE (-6250 2825);
FORCEPROP 2 LAST CDS_LIB mstr_symbols
J 0
(-6250 2825);
PAINT ORANGE (-6250 2825);
DISPLAY INVISIBLE (-6250 2825);
FORCEPROP 1 LAST SIZE 1B
J 0
(-6175 2775);
DISPLAY 0.893617 (-6175 2775);
PAINT GREEN (-6175 2775);
DISPLAY INVISIBLE (-6175 2775);
FORCEPROP 1 LAST BODY_TYPE PLUMBING
J 0
(-6295 2782);
DISPLAY 0.340426 (-6295 2782);
PAINT GREEN (-6295 2782);
DISPLAY INVISIBLE (-6295 2782);
FORCEPROP 1 LAST PATH I113
J 0
(-6175 2825);
DISPLAY 0.872340 (-6175 2825);
PAINT AQUA (-6175 2825);
DISPLAY INVISIBLE (-6175 2825);
FORCEPROP 2 LAST ROOM PVCCIN_CPU1_DECAP_VR
J 0
(-6800 2900);
PAINT ORANGE (-6800 2900);
DISPLAY INVISIBLE (-6800 2900);
FORCEPROP 1 LAST HDL_POWER GND
J 0
(-6250 2975);
DISPLAY 0.893617 (-6250 2975);
PAINT GREEN (-6250 2975);
DISPLAY INVISIBLE (-6250 2975);
FORCEADD CAP_A..1
(-6600 3125);
FORCEPROP 1 LAST LOCATION C2D17
J 0
(-6550 3225);
DISPLAY 0.617021 (-6550 3225);
PAINT AQUA (-6550 3225);
FORCEPROP 1 LAST PART_NUMBER E15431-004
J 0
(-6550 2975);
DISPLAY 0.617021 (-6550 2975);
PAINT BLUE (-6550 2975);
FORCEPROP 1 LAST VALUE 22.0UF
J 0
(-6550 3175);
DISPLAY 0.617021 (-6550 3175);
PAINT SKYBLUE (-6550 3175);
FORCEPROP 1 LAST TOLERANCE 20%
J 0
(-6550 3075);
DISPLAY 0.617021 (-6550 3075);
PAINT SKYBLUE (-6550 3075);
FORCEPROP 1 LAST PACK_TYPE 0603V
J 0
(-6550 2925);
DISPLAY 0.617021 (-6550 2925);
PAINT SKYBLUE (-6550 2925);
FORCEPROP 1 LAST VOLTAGE 4V
J 0
(-6550 3125);
DISPLAY 0.617021 (-6550 3125);
PAINT SKYBLUE (-6550 3125);
FORCEPROP 1 LAST MATERIAL X6S
J 0
(-6550 3025);
DISPLAY 0.617021 (-6550 3025);
PAINT SKYBLUE (-6550 3025);
FORCEPROP 1 LASTPIN (-6600 3225) $PN 1
J 0
(-6590 3205);
DISPLAY 0.617021 (-6590 3205);
PAINT GREEN (-6590 3205);
FORCEPROP 1 LASTPIN (-6600 3025) $PN 2
J 0
(-6590 3005);
DISPLAY 0.617021 (-6590 3005);
PAINT GREEN (-6590 3005);
FORCEPROP 2 LAST CDS_LOCATION C2D17
J 0
(-6550 3225);
DISPLAY 0.617021 (-6550 3225);
PAINT AQUA (-6550 3225);
DISPLAY INVISIBLE (-6550 3225);
FORCEPROP 2 LAST BOM_COST PROC
J 0
(-6600 3125);
PAINT MONO (-6600 3125);
DISPLAY INVISIBLE (-6600 3125);
FORCEPROP 2 LAST CDS_LIB dev_discrete
J 0
(-6600 3125);
PAINT ORANGE (-6600 3125);
DISPLAY INVISIBLE (-6600 3125);
FORCEPROP 2 LAST CDS_SEC 1
J 0
(-6550 3325);
PAINT MONO (-6550 3325);
DISPLAY INVISIBLE (-6550 3325);
FORCEPROP 2 LAST $SEC 1
J 0
(-6550 3325);
PAINT MONO (-6550 3325);
DISPLAY INVISIBLE (-6550 3325);
FORCEPROP 1 LAST PATH I114
J 0
(-6550 3275);
DISPLAY 0.978723 (-6550 3275);
PAINT WHITE (-6550 3275);
DISPLAY INVISIBLE (-6550 3275);
FORCEPROP 2 LAST ROOM PVCCIN_CPU1_DECAP_VR
J 0
(-6550 3225);
PAINT ORANGE (-6550 3225);
DISPLAY INVISIBLE (-6550 3225);
FORCEADD CAP_A..1
(-6950 3150);
FORCEPROP 1 LAST LOCATION C2D1
J 0
(-6900 3250);
DISPLAY 0.617021 (-6900 3250);
PAINT AQUA (-6900 3250);
FORCEPROP 1 LAST PART_NUMBER E15431-004
J 0
(-6900 3000);
DISPLAY 0.617021 (-6900 3000);
PAINT BLUE (-6900 3000);
FORCEPROP 1 LAST VALUE 22.0UF
J 0
(-6900 3200);
DISPLAY 0.617021 (-6900 3200);
PAINT SKYBLUE (-6900 3200);
FORCEPROP 1 LAST TOLERANCE 20%
J 0
(-6900 3100);
DISPLAY 0.617021 (-6900 3100);
PAINT SKYBLUE (-6900 3100);
FORCEPROP 1 LAST PACK_TYPE 0603V
J 0
(-6900 2950);
DISPLAY 0.617021 (-6900 2950);
PAINT SKYBLUE (-6900 2950);
FORCEPROP 1 LAST VOLTAGE 4V
J 0
(-6900 3150);
DISPLAY 0.617021 (-6900 3150);
PAINT SKYBLUE (-6900 3150);
FORCEPROP 1 LAST MATERIAL X6S
J 0
(-6900 3050);
DISPLAY 0.617021 (-6900 3050);
PAINT SKYBLUE (-6900 3050);
FORCEPROP 1 LASTPIN (-6950 3250) $PN 1
J 0
(-6940 3230);
DISPLAY 0.617021 (-6940 3230);
PAINT GREEN (-6940 3230);
FORCEPROP 1 LASTPIN (-6950 3050) $PN 2
J 0
(-6940 3030);
DISPLAY 0.617021 (-6940 3030);
PAINT GREEN (-6940 3030);
FORCEPROP 2 LAST CDS_LOCATION C2D1
J 0
(-6900 3250);
DISPLAY 0.617021 (-6900 3250);
PAINT AQUA (-6900 3250);
DISPLAY INVISIBLE (-6900 3250);
FORCEPROP 2 LAST BOM_COST PROC
J 0
(-6950 3150);
PAINT MONO (-6950 3150);
DISPLAY INVISIBLE (-6950 3150);
FORCEPROP 2 LAST CDS_LIB dev_discrete
J 0
(-6950 3150);
PAINT ORANGE (-6950 3150);
DISPLAY INVISIBLE (-6950 3150);
FORCEPROP 2 LAST CDS_SEC 1
J 0
(-6900 3350);
PAINT MONO (-6900 3350);
DISPLAY INVISIBLE (-6900 3350);
FORCEPROP 2 LAST $SEC 1
J 0
(-6900 3350);
PAINT MONO (-6900 3350);
DISPLAY INVISIBLE (-6900 3350);
FORCEPROP 1 LAST PATH I116
J 0
(-6900 3300);
DISPLAY 0.978723 (-6900 3300);
PAINT WHITE (-6900 3300);
DISPLAY INVISIBLE (-6900 3300);
FORCEPROP 2 LAST ROOM PVCCIN_CPU1_DECAP_VR
J 0
(-6900 3250);
PAINT ORANGE (-6900 3250);
DISPLAY INVISIBLE (-6900 3250);
FORCEADD CAP..1
(-7050 2200);
FORCEPROP 1 LAST LOCATION C8P26
J 0
(-7000 2300);
DISPLAY 0.617021 (-7000 2300);
PAINT AQUA (-7000 2300);
FORCEPROP 1 LAST PART_NUMBER C95333-006
J 0
(-7000 2100);
DISPLAY 0.617021 (-7000 2100);
PAINT BLUE (-7000 2100);
FORCEPROP 1 LAST VALUE 47UF
J 0
(-7000 2250);
DISPLAY 0.617021 (-7000 2250);
PAINT SKYBLUE (-7000 2250);
FORCEPROP 1 LAST TOLERANCE 20%
J 0
(-7000 2150);
DISPLAY 0.617021 (-7000 2150);
PAINT SKYBLUE (-7000 2150);
FORCEPROP 1 LAST PACK_TYPE 0805
J 0
(-7000 2050);
DISPLAY 0.617021 (-7000 2050);
PAINT SKYBLUE (-7000 2050);
FORCEPROP 1 LASTPIN (-7050 2100) $PN 2
J 0
(-7040 2080);
DISPLAY 0.617021 (-7040 2080);
PAINT GREEN (-7040 2080);
FORCEPROP 1 LASTPIN (-7050 2300) $PN 1
J 0
(-7040 2280);
DISPLAY 0.617021 (-7040 2280);
PAINT GREEN (-7040 2280);
FORCEPROP 1 LAST VOLTAGE 4V
J 0
(-7000 2200);
PAINT SKYBLUE (-7000 2200);
DISPLAY INVISIBLE (-7000 2200);
FORCEPROP 1 LAST MATERIAL X6S
J 0
(-7000 2100);
PAINT SKYBLUE (-7000 2100);
DISPLAY INVISIBLE (-7000 2100);
FORCEPROP 2 LAST CDS_LIB mstr_discrete
J 0
(-7050 2200);
PAINT ORANGE (-7050 2200);
DISPLAY INVISIBLE (-7050 2200);
FORCEPROP 2 LAST BOM_COST PROC
J 0
(-7050 2200);
PAINT MONO (-7050 2200);
DISPLAY INVISIBLE (-7050 2200);
FORCEPROP 2 LAST CDS_SEC 1
J 0
(-7000 2400);
PAINT MONO (-7000 2400);
DISPLAY INVISIBLE (-7000 2400);
FORCEPROP 2 LAST $SEC 1
J 0
(-7000 2400);
PAINT MONO (-7000 2400);
DISPLAY INVISIBLE (-7000 2400);
FORCEPROP 2 LAST CDS_LOCATION C8P26
J 0
(-7000 2300);
DISPLAY 0.617021 (-7000 2300);
PAINT AQUA (-7000 2300);
DISPLAY INVISIBLE (-7000 2300);
FORCEPROP 1 LAST PATH I118
J 0
(-7000 2350);
DISPLAY 0.978723 (-7000 2350);
PAINT WHITE (-7000 2350);
DISPLAY INVISIBLE (-7000 2350);
FORCEPROP 2 LAST ROOM PVCCIN_CPU1_DECAP_VR
J 0
(-7000 2300);
PAINT ORANGE (-7000 2300);
DISPLAY INVISIBLE (-7000 2300);
FORCEADD CAP_A..1
(-7325 3775);
FORCEPROP 1 LAST LOCATION C2D37
J 0
(-7275 3875);
DISPLAY 0.617021 (-7275 3875);
PAINT AQUA (-7275 3875);
FORCEPROP 1 LAST PART_NUMBER E15431-004
J 0
(-7275 3625);
DISPLAY 0.617021 (-7275 3625);
PAINT BLUE (-7275 3625);
FORCEPROP 1 LAST VALUE 22.0UF
J 0
(-7275 3825);
DISPLAY 0.617021 (-7275 3825);
PAINT SKYBLUE (-7275 3825);
FORCEPROP 1 LAST TOLERANCE 20%
J 0
(-7275 3725);
DISPLAY 0.617021 (-7275 3725);
PAINT SKYBLUE (-7275 3725);
FORCEPROP 1 LAST PACK_TYPE 0603V
J 0
(-7275 3575);
DISPLAY 0.617021 (-7275 3575);
PAINT SKYBLUE (-7275 3575);
FORCEPROP 1 LAST VOLTAGE 4V
J 0
(-7275 3775);
DISPLAY 0.617021 (-7275 3775);
PAINT SKYBLUE (-7275 3775);
FORCEPROP 1 LAST MATERIAL X6S
J 0
(-7275 3675);
DISPLAY 0.617021 (-7275 3675);
PAINT SKYBLUE (-7275 3675);
FORCEPROP 1 LASTPIN (-7325 3875) $PN 1
J 0
(-7315 3855);
DISPLAY 0.617021 (-7315 3855);
PAINT GREEN (-7315 3855);
FORCEPROP 1 LASTPIN (-7325 3675) $PN 2
J 0
(-7315 3655);
DISPLAY 0.617021 (-7315 3655);
PAINT GREEN (-7315 3655);
FORCEPROP 2 LAST CDS_LOCATION C2D37
J 0
(-7275 3875);
DISPLAY 0.617021 (-7275 3875);
PAINT AQUA (-7275 3875);
DISPLAY INVISIBLE (-7275 3875);
FORCEPROP 2 LAST BOM_COST PROC
J 0
(-7325 3775);
PAINT MONO (-7325 3775);
DISPLAY INVISIBLE (-7325 3775);
FORCEPROP 2 LAST CDS_LIB dev_discrete
J 0
(-7325 3775);
PAINT ORANGE (-7325 3775);
DISPLAY INVISIBLE (-7325 3775);
FORCEPROP 2 LAST CDS_SEC 1
J 0
(-7275 3975);
PAINT MONO (-7275 3975);
DISPLAY INVISIBLE (-7275 3975);
FORCEPROP 2 LAST $SEC 1
J 0
(-7275 3975);
PAINT MONO (-7275 3975);
DISPLAY INVISIBLE (-7275 3975);
FORCEPROP 1 LAST PATH I119
J 0
(-7275 3925);
DISPLAY 0.978723 (-7275 3925);
PAINT WHITE (-7275 3925);
DISPLAY INVISIBLE (-7275 3925);
FORCEPROP 2 LAST ROOM PVCCIN_CPU1_DECAP_VR
J 0
(-7275 3875);
PAINT ORANGE (-7275 3875);
DISPLAY INVISIBLE (-7275 3875);
FORCEADD CAP_A..1
(-7675 3775);
FORCEPROP 1 LAST LOCATION C2D34
J 0
(-7625 3875);
DISPLAY 0.617021 (-7625 3875);
PAINT AQUA (-7625 3875);
FORCEPROP 1 LAST PART_NUMBER E15431-004
J 0
(-7625 3625);
DISPLAY 0.617021 (-7625 3625);
PAINT BLUE (-7625 3625);
FORCEPROP 1 LAST VALUE 22.0UF
J 0
(-7625 3825);
DISPLAY 0.617021 (-7625 3825);
PAINT SKYBLUE (-7625 3825);
FORCEPROP 1 LAST TOLERANCE 20%
J 0
(-7625 3725);
DISPLAY 0.617021 (-7625 3725);
PAINT SKYBLUE (-7625 3725);
FORCEPROP 1 LAST PACK_TYPE 0603V
J 0
(-7625 3575);
DISPLAY 0.617021 (-7625 3575);
PAINT SKYBLUE (-7625 3575);
FORCEPROP 1 LAST VOLTAGE 4V
J 0
(-7625 3775);
DISPLAY 0.617021 (-7625 3775);
PAINT SKYBLUE (-7625 3775);
FORCEPROP 1 LAST MATERIAL X6S
J 0
(-7625 3675);
DISPLAY 0.617021 (-7625 3675);
PAINT SKYBLUE (-7625 3675);
FORCEPROP 1 LASTPIN (-7675 3875) $PN 1
J 0
(-7665 3855);
DISPLAY 0.617021 (-7665 3855);
PAINT GREEN (-7665 3855);
FORCEPROP 1 LASTPIN (-7675 3675) $PN 2
J 0
(-7665 3655);
DISPLAY 0.617021 (-7665 3655);
PAINT GREEN (-7665 3655);
FORCEPROP 2 LAST CDS_LOCATION C2D34
J 0
(-7625 3875);
DISPLAY 0.617021 (-7625 3875);
PAINT AQUA (-7625 3875);
DISPLAY INVISIBLE (-7625 3875);
FORCEPROP 2 LAST BOM_COST PROC
J 0
(-7675 3775);
PAINT MONO (-7675 3775);
DISPLAY INVISIBLE (-7675 3775);
FORCEPROP 2 LAST CDS_LIB dev_discrete
J 0
(-7675 3775);
PAINT ORANGE (-7675 3775);
DISPLAY INVISIBLE (-7675 3775);
FORCEPROP 2 LAST CDS_SEC 1
J 0
(-7625 3975);
PAINT MONO (-7625 3975);
DISPLAY INVISIBLE (-7625 3975);
FORCEPROP 2 LAST $SEC 1
J 0
(-7625 3975);
PAINT MONO (-7625 3975);
DISPLAY INVISIBLE (-7625 3975);
FORCEPROP 1 LAST PATH I122
J 0
(-7625 3925);
DISPLAY 0.978723 (-7625 3925);
PAINT WHITE (-7625 3925);
DISPLAY INVISIBLE (-7625 3925);
FORCEPROP 2 LAST ROOM PVCCIN_CPU1_DECAP_VR
J 0
(-7625 3875);
PAINT ORANGE (-7625 3875);
DISPLAY INVISIBLE (-7625 3875);
FORCEADD CAP_A..1
(-7275 3150);
FORCEPROP 1 LAST LOCATION C2D45
J 0
(-7225 3250);
DISPLAY 0.617021 (-7225 3250);
PAINT AQUA (-7225 3250);
FORCEPROP 1 LAST PART_NUMBER E15431-004
J 0
(-7225 3000);
DISPLAY 0.617021 (-7225 3000);
PAINT BLUE (-7225 3000);
FORCEPROP 1 LAST VALUE 22.0UF
J 0
(-7225 3200);
DISPLAY 0.617021 (-7225 3200);
PAINT SKYBLUE (-7225 3200);
FORCEPROP 1 LAST TOLERANCE 20%
J 0
(-7225 3100);
DISPLAY 0.617021 (-7225 3100);
PAINT SKYBLUE (-7225 3100);
FORCEPROP 1 LAST PACK_TYPE 0603V
J 0
(-7225 2950);
DISPLAY 0.617021 (-7225 2950);
PAINT SKYBLUE (-7225 2950);
FORCEPROP 1 LAST VOLTAGE 4V
J 0
(-7225 3150);
DISPLAY 0.617021 (-7225 3150);
PAINT SKYBLUE (-7225 3150);
FORCEPROP 1 LAST MATERIAL X6S
J 0
(-7225 3050);
DISPLAY 0.617021 (-7225 3050);
PAINT SKYBLUE (-7225 3050);
FORCEPROP 1 LASTPIN (-7275 3250) $PN 1
J 0
(-7265 3230);
DISPLAY 0.617021 (-7265 3230);
PAINT GREEN (-7265 3230);
FORCEPROP 1 LASTPIN (-7275 3050) $PN 2
J 0
(-7265 3030);
DISPLAY 0.617021 (-7265 3030);
PAINT GREEN (-7265 3030);
FORCEPROP 2 LAST CDS_LOCATION C2D45
J 0
(-7225 3250);
DISPLAY 0.617021 (-7225 3250);
PAINT AQUA (-7225 3250);
DISPLAY INVISIBLE (-7225 3250);
FORCEPROP 2 LAST BOM_COST PROC
J 0
(-7275 3150);
PAINT MONO (-7275 3150);
DISPLAY INVISIBLE (-7275 3150);
FORCEPROP 2 LAST CDS_LIB dev_discrete
J 0
(-7275 3150);
PAINT ORANGE (-7275 3150);
DISPLAY INVISIBLE (-7275 3150);
FORCEPROP 2 LAST CDS_SEC 1
J 0
(-7225 3350);
PAINT MONO (-7225 3350);
DISPLAY INVISIBLE (-7225 3350);
FORCEPROP 2 LAST $SEC 1
J 0
(-7225 3350);
PAINT MONO (-7225 3350);
DISPLAY INVISIBLE (-7225 3350);
FORCEPROP 1 LAST PATH I123
J 0
(-7225 3300);
DISPLAY 0.978723 (-7225 3300);
PAINT WHITE (-7225 3300);
DISPLAY INVISIBLE (-7225 3300);
FORCEPROP 2 LAST ROOM PVCCIN_CPU1_DECAP_VR
J 0
(-7225 3250);
PAINT ORANGE (-7225 3250);
DISPLAY INVISIBLE (-7225 3250);
FORCEADD CAP_A..1
(-7625 3150);
FORCEPROP 1 LAST LOCATION C2D16
J 0
(-7575 3250);
DISPLAY 0.617021 (-7575 3250);
PAINT AQUA (-7575 3250);
FORCEPROP 1 LAST PART_NUMBER E15431-004
J 0
(-7575 3000);
DISPLAY 0.617021 (-7575 3000);
PAINT BLUE (-7575 3000);
FORCEPROP 1 LAST VALUE 22.0UF
J 0
(-7575 3200);
DISPLAY 0.617021 (-7575 3200);
PAINT SKYBLUE (-7575 3200);
FORCEPROP 1 LAST TOLERANCE 20%
J 0
(-7575 3100);
DISPLAY 0.617021 (-7575 3100);
PAINT SKYBLUE (-7575 3100);
FORCEPROP 1 LAST PACK_TYPE 0603V
J 0
(-7575 2950);
DISPLAY 0.617021 (-7575 2950);
PAINT SKYBLUE (-7575 2950);
FORCEPROP 1 LAST VOLTAGE 4V
J 0
(-7575 3150);
DISPLAY 0.617021 (-7575 3150);
PAINT SKYBLUE (-7575 3150);
FORCEPROP 1 LAST MATERIAL X6S
J 0
(-7575 3050);
DISPLAY 0.617021 (-7575 3050);
PAINT SKYBLUE (-7575 3050);
FORCEPROP 1 LASTPIN (-7625 3250) $PN 1
J 0
(-7615 3230);
DISPLAY 0.617021 (-7615 3230);
PAINT GREEN (-7615 3230);
FORCEPROP 1 LASTPIN (-7625 3050) $PN 2
J 0
(-7615 3030);
DISPLAY 0.617021 (-7615 3030);
PAINT GREEN (-7615 3030);
FORCEPROP 2 LAST CDS_LOCATION C2D16
J 0
(-7575 3250);
DISPLAY 0.617021 (-7575 3250);
PAINT AQUA (-7575 3250);
DISPLAY INVISIBLE (-7575 3250);
FORCEPROP 2 LAST BOM_COST PROC
J 0
(-7625 3150);
PAINT MONO (-7625 3150);
DISPLAY INVISIBLE (-7625 3150);
FORCEPROP 2 LAST CDS_LIB dev_discrete
J 0
(-7625 3150);
PAINT ORANGE (-7625 3150);
DISPLAY INVISIBLE (-7625 3150);
FORCEPROP 2 LAST CDS_SEC 1
J 0
(-7575 3350);
PAINT MONO (-7575 3350);
DISPLAY INVISIBLE (-7575 3350);
FORCEPROP 2 LAST $SEC 1
J 0
(-7575 3350);
PAINT MONO (-7575 3350);
DISPLAY INVISIBLE (-7575 3350);
FORCEPROP 1 LAST PATH I124
J 0
(-7575 3300);
DISPLAY 0.978723 (-7575 3300);
PAINT WHITE (-7575 3300);
DISPLAY INVISIBLE (-7575 3300);
FORCEPROP 2 LAST ROOM PVCCIN_CPU1_DECAP_VR
J 0
(-7575 3250);
PAINT ORANGE (-7575 3250);
DISPLAY INVISIBLE (-7575 3250);
FORCEADD CAP..1
(-7375 2200);
FORCEPROP 1 LAST LOCATION C8P29
J 0
(-7325 2300);
DISPLAY 0.617021 (-7325 2300);
PAINT AQUA (-7325 2300);
FORCEPROP 1 LAST PART_NUMBER C95333-006
J 0
(-7350 2100);
DISPLAY 0.617021 (-7350 2100);
PAINT BLUE (-7350 2100);
FORCEPROP 1 LAST VALUE 47UF
J 0
(-7325 2250);
DISPLAY 0.617021 (-7325 2250);
PAINT SKYBLUE (-7325 2250);
FORCEPROP 1 LAST TOLERANCE 20%
J 0
(-7325 2150);
DISPLAY 0.617021 (-7325 2150);
PAINT SKYBLUE (-7325 2150);
FORCEPROP 1 LAST PACK_TYPE 0805
J 0
(-7325 2050);
DISPLAY 0.617021 (-7325 2050);
PAINT SKYBLUE (-7325 2050);
FORCEPROP 1 LASTPIN (-7375 2100) $PN 2
J 0
(-7365 2080);
DISPLAY 0.617021 (-7365 2080);
PAINT GREEN (-7365 2080);
FORCEPROP 1 LASTPIN (-7375 2300) $PN 1
J 0
(-7365 2280);
DISPLAY 0.617021 (-7365 2280);
PAINT GREEN (-7365 2280);
FORCEPROP 1 LAST VOLTAGE 4V
J 0
(-7325 2200);
PAINT SKYBLUE (-7325 2200);
DISPLAY INVISIBLE (-7325 2200);
FORCEPROP 1 LAST MATERIAL X6S
J 0
(-7325 2100);
PAINT SKYBLUE (-7325 2100);
DISPLAY INVISIBLE (-7325 2100);
FORCEPROP 2 LAST CDS_LIB mstr_discrete
J 0
(-7375 2200);
PAINT ORANGE (-7375 2200);
DISPLAY INVISIBLE (-7375 2200);
FORCEPROP 2 LAST BOM_COST PROC
J 0
(-7375 2200);
PAINT MONO (-7375 2200);
DISPLAY INVISIBLE (-7375 2200);
FORCEPROP 2 LAST CDS_SEC 1
J 0
(-7325 2400);
PAINT MONO (-7325 2400);
DISPLAY INVISIBLE (-7325 2400);
FORCEPROP 2 LAST $SEC 1
J 0
(-7325 2400);
PAINT MONO (-7325 2400);
DISPLAY INVISIBLE (-7325 2400);
FORCEPROP 2 LAST CDS_LOCATION C8P29
J 0
(-7325 2300);
DISPLAY 0.617021 (-7325 2300);
PAINT AQUA (-7325 2300);
DISPLAY INVISIBLE (-7325 2300);
FORCEPROP 1 LAST PATH I125
J 0
(-7325 2350);
DISPLAY 0.978723 (-7325 2350);
PAINT WHITE (-7325 2350);
DISPLAY INVISIBLE (-7325 2350);
FORCEPROP 2 LAST ROOM PVCCIN_CPU1_DECAP_VR
J 0
(-7300 2300);
PAINT ORANGE (-7300 2300);
DISPLAY INVISIBLE (-7300 2300);
FORCEADD CAP..1
(-7725 2200);
FORCEPROP 1 LAST LOCATION C8P10
J 0
(-7675 2300);
DISPLAY 0.617021 (-7675 2300);
PAINT AQUA (-7675 2300);
FORCEPROP 1 LAST PART_NUMBER C95333-006
R 1
J 0
(-7775 2025);
DISPLAY 0.617021 (-7775 2025);
PAINT BLUE (-7775 2025);
FORCEPROP 1 LAST VALUE 47UF
J 0
(-7675 2250);
DISPLAY 0.617021 (-7675 2250);
PAINT SKYBLUE (-7675 2250);
FORCEPROP 1 LAST TOLERANCE 20%
J 0
(-7675 2150);
DISPLAY 0.617021 (-7675 2150);
PAINT SKYBLUE (-7675 2150);
FORCEPROP 1 LAST PACK_TYPE 0805
J 0
(-7675 2050);
DISPLAY 0.617021 (-7675 2050);
PAINT SKYBLUE (-7675 2050);
FORCEPROP 1 LAST MATERIAL X6S
J 0
(-7675 2100);
DISPLAY 0.617021 (-7675 2100);
PAINT SKYBLUE (-7675 2100);
FORCEPROP 1 LASTPIN (-7725 2100) $PN 2
J 0
(-7715 2080);
DISPLAY 0.617021 (-7715 2080);
PAINT GREEN (-7715 2080);
FORCEPROP 1 LASTPIN (-7725 2300) $PN 1
J 0
(-7715 2280);
DISPLAY 0.617021 (-7715 2280);
PAINT GREEN (-7715 2280);
FORCEPROP 1 LAST VOLTAGE 4V
J 0
(-7675 2200);
PAINT SKYBLUE (-7675 2200);
DISPLAY INVISIBLE (-7675 2200);
FORCEPROP 2 LAST CDS_LIB mstr_discrete
J 0
(-7725 2200);
PAINT ORANGE (-7725 2200);
DISPLAY INVISIBLE (-7725 2200);
FORCEPROP 2 LAST BOM_COST PROC
J 0
(-7725 2200);
PAINT MONO (-7725 2200);
DISPLAY INVISIBLE (-7725 2200);
FORCEPROP 2 LAST CDS_SEC 1
J 0
(-7675 2400);
PAINT MONO (-7675 2400);
DISPLAY INVISIBLE (-7675 2400);
FORCEPROP 2 LAST $SEC 1
J 0
(-7675 2400);
PAINT MONO (-7675 2400);
DISPLAY INVISIBLE (-7675 2400);
FORCEPROP 2 LAST CDS_LOCATION C8P10
J 0
(-7675 2300);
DISPLAY 0.617021 (-7675 2300);
PAINT AQUA (-7675 2300);
DISPLAY INVISIBLE (-7675 2300);
FORCEPROP 1 LAST PATH I127
J 0
(-7675 2350);
DISPLAY 0.978723 (-7675 2350);
PAINT WHITE (-7675 2350);
DISPLAY INVISIBLE (-7675 2350);
FORCEPROP 2 LAST ROOM PVCCIN_CPU1_DECAP_VR
J 0
(-7675 2300);
PAINT ORANGE (-7675 2300);
DISPLAY INVISIBLE (-7675 2300);
FORCEADD GND..1
(-6350 1875);
FORCEPROP 3 LASTPIN (-6350 1925) SIG_NAME GND\g
J 0
(-6340 1935);
DISPLAY 0.659574 (-6340 1935);
PAINT MONO (-6340 1935);
DISPLAY INVISIBLE (-6340 1935);
FORCEPROP 1 LAST VOLTAGE 0
J 0
(-6350 1875);
PAINT SKYBLUE (-6350 1875);
DISPLAY INVISIBLE (-6350 1875);
FORCEPROP 1 LAST SIZE 1B
J 0
(-6275 1825);
DISPLAY 0.893617 (-6275 1825);
PAINT GREEN (-6275 1825);
DISPLAY INVISIBLE (-6275 1825);
FORCEPROP 2 LAST CDS_LIB mstr_symbols
J 0
(-6350 1875);
PAINT ORANGE (-6350 1875);
DISPLAY INVISIBLE (-6350 1875);
FORCEPROP 1 LAST BODY_TYPE PLUMBING
J 0
(-6395 1832);
DISPLAY 0.340426 (-6395 1832);
PAINT GREEN (-6395 1832);
DISPLAY INVISIBLE (-6395 1832);
FORCEPROP 1 LAST PATH I128
J 0
(-6275 1875);
DISPLAY 0.872340 (-6275 1875);
PAINT AQUA (-6275 1875);
DISPLAY INVISIBLE (-6275 1875);
FORCEPROP 2 LAST ROOM PVCCIN_CPU1_DECAP_VR
J 0
(-6900 1950);
PAINT ORANGE (-6900 1950);
DISPLAY INVISIBLE (-6900 1950);
FORCEPROP 1 LAST HDL_POWER GND
J 0
(-6350 2025);
DISPLAY 0.893617 (-6350 2025);
PAINT GREEN (-6350 2025);
DISPLAY INVISIBLE (-6350 2025);
FORCEADD CAP..1
(-6350 1550);
FORCEPROP 1 LAST LOCATION C8P16
J 0
(-6300 1650);
DISPLAY 0.617021 (-6300 1650);
PAINT AQUA (-6300 1650);
FORCEPROP 1 LAST PART_NUMBER C95333-006
R 1
J 0
(-6400 1375);
DISPLAY 0.617021 (-6400 1375);
PAINT BLUE (-6400 1375);
FORCEPROP 1 LAST VALUE 47UF
J 0
(-6300 1600);
DISPLAY 0.617021 (-6300 1600);
PAINT SKYBLUE (-6300 1600);
FORCEPROP 1 LAST TOLERANCE 20%
J 0
(-6300 1500);
DISPLAY 0.617021 (-6300 1500);
PAINT SKYBLUE (-6300 1500);
FORCEPROP 1 LAST PACK_TYPE 0805
J 0
(-6300 1400);
DISPLAY 0.617021 (-6300 1400);
PAINT SKYBLUE (-6300 1400);
FORCEPROP 1 LASTPIN (-6350 1450) $PN 2
J 0
(-6340 1430);
DISPLAY 0.617021 (-6340 1430);
PAINT GREEN (-6340 1430);
FORCEPROP 1 LASTPIN (-6350 1650) $PN 1
J 0
(-6340 1630);
DISPLAY 0.617021 (-6340 1630);
PAINT GREEN (-6340 1630);
FORCEPROP 1 LAST VOLTAGE 4V
J 0
(-6300 1550);
PAINT SKYBLUE (-6300 1550);
DISPLAY INVISIBLE (-6300 1550);
FORCEPROP 1 LAST MATERIAL X6S
J 0
(-6300 1450);
PAINT SKYBLUE (-6300 1450);
DISPLAY INVISIBLE (-6300 1450);
FORCEPROP 2 LAST BOM_COST PROC
J 0
(-6350 1550);
PAINT MONO (-6350 1550);
DISPLAY INVISIBLE (-6350 1550);
FORCEPROP 2 LAST CDS_LIB mstr_discrete
J 0
(-6350 1550);
PAINT ORANGE (-6350 1550);
DISPLAY INVISIBLE (-6350 1550);
FORCEPROP 2 LAST CDS_SEC 1
J 0
(-6300 1750);
DISPLAY 1.021277 (-6300 1750);
PAINT ORANGE (-6300 1750);
DISPLAY INVISIBLE (-6300 1750);
FORCEPROP 2 LAST $SEC 1
J 0
(-6300 1750);
DISPLAY 0.680851 (-6300 1750);
PAINT MONO (-6300 1750);
DISPLAY INVISIBLE (-6300 1750);
FORCEPROP 2 LAST CDS_LOCATION C8P16
J 0
(-6300 1650);
DISPLAY 0.617021 (-6300 1650);
PAINT AQUA (-6300 1650);
DISPLAY INVISIBLE (-6300 1650);
FORCEPROP 1 LAST PATH I129
J 0
(-6300 1700);
DISPLAY 0.978723 (-6300 1700);
PAINT WHITE (-6300 1700);
DISPLAY INVISIBLE (-6300 1700);
FORCEPROP 2 LAST ROOM PVCCIN_CPU1_DECAP_VR
J 0
(-6300 1650);
PAINT ORANGE (-6300 1650);
DISPLAY INVISIBLE (-6300 1650);
FORCEADD GND..1
(-6350 1225);
FORCEPROP 3 LASTPIN (-6350 1275) SIG_NAME GND\g
J 0
(-6340 1285);
DISPLAY 0.659574 (-6340 1285);
PAINT MONO (-6340 1285);
DISPLAY INVISIBLE (-6340 1285);
FORCEPROP 1 LAST VOLTAGE 0
J 0
(-6350 1225);
PAINT SKYBLUE (-6350 1225);
DISPLAY INVISIBLE (-6350 1225);
FORCEPROP 1 LAST SIZE 1B
J 0
(-6275 1175);
DISPLAY 0.893617 (-6275 1175);
PAINT GREEN (-6275 1175);
DISPLAY INVISIBLE (-6275 1175);
FORCEPROP 2 LAST CDS_LIB mstr_symbols
J 0
(-6350 1225);
PAINT ORANGE (-6350 1225);
DISPLAY INVISIBLE (-6350 1225);
FORCEPROP 1 LAST BODY_TYPE PLUMBING
J 0
(-6395 1182);
DISPLAY 0.340426 (-6395 1182);
PAINT GREEN (-6395 1182);
DISPLAY INVISIBLE (-6395 1182);
FORCEPROP 1 LAST PATH I130
J 0
(-6275 1225);
DISPLAY 0.872340 (-6275 1225);
PAINT AQUA (-6275 1225);
DISPLAY INVISIBLE (-6275 1225);
FORCEPROP 2 LAST ROOM PVCCIN_CPU1_DECAP_VR
J 0
(-6900 1300);
PAINT ORANGE (-6900 1300);
DISPLAY INVISIBLE (-6900 1300);
FORCEPROP 1 LAST HDL_POWER GND
J 0
(-6350 1375);
DISPLAY 0.893617 (-6350 1375);
PAINT GREEN (-6350 1375);
DISPLAY INVISIBLE (-6350 1375);
FORCEADD CAP..1
(-6700 1550);
FORCEPROP 1 LAST LOCATION C8P33
J 0
(-6650 1650);
DISPLAY 0.617021 (-6650 1650);
PAINT AQUA (-6650 1650);
FORCEPROP 1 LAST PART_NUMBER C95333-006
R 1
J 0
(-6750 1375);
DISPLAY 0.617021 (-6750 1375);
PAINT BLUE (-6750 1375);
FORCEPROP 1 LAST VALUE 47UF
J 0
(-6650 1600);
DISPLAY 0.617021 (-6650 1600);
PAINT SKYBLUE (-6650 1600);
FORCEPROP 1 LAST TOLERANCE 20%
J 0
(-6650 1500);
DISPLAY 0.617021 (-6650 1500);
PAINT SKYBLUE (-6650 1500);
FORCEPROP 1 LAST PACK_TYPE 0805
J 0
(-6650 1400);
DISPLAY 0.617021 (-6650 1400);
PAINT SKYBLUE (-6650 1400);
FORCEPROP 1 LASTPIN (-6700 1450) $PN 2
J 0
(-6690 1430);
DISPLAY 0.617021 (-6690 1430);
PAINT GREEN (-6690 1430);
FORCEPROP 1 LASTPIN (-6700 1650) $PN 1
J 0
(-6690 1630);
DISPLAY 0.617021 (-6690 1630);
PAINT GREEN (-6690 1630);
FORCEPROP 1 LAST VOLTAGE 4V
J 0
(-6650 1550);
PAINT SKYBLUE (-6650 1550);
DISPLAY INVISIBLE (-6650 1550);
FORCEPROP 1 LAST MATERIAL X6S
J 0
(-6650 1450);
PAINT SKYBLUE (-6650 1450);
DISPLAY INVISIBLE (-6650 1450);
FORCEPROP 2 LAST BOM_COST PROC
J 0
(-6700 1550);
PAINT MONO (-6700 1550);
DISPLAY INVISIBLE (-6700 1550);
FORCEPROP 2 LAST CDS_LIB mstr_discrete
J 0
(-6700 1550);
PAINT ORANGE (-6700 1550);
DISPLAY INVISIBLE (-6700 1550);
FORCEPROP 2 LAST CDS_SEC 1
J 0
(-6650 1750);
DISPLAY 1.021277 (-6650 1750);
PAINT ORANGE (-6650 1750);
DISPLAY INVISIBLE (-6650 1750);
FORCEPROP 2 LAST $SEC 1
J 0
(-6650 1750);
DISPLAY 0.680851 (-6650 1750);
PAINT MONO (-6650 1750);
DISPLAY INVISIBLE (-6650 1750);
FORCEPROP 2 LAST CDS_LOCATION C8P33
J 0
(-6650 1650);
DISPLAY 0.617021 (-6650 1650);
PAINT AQUA (-6650 1650);
DISPLAY INVISIBLE (-6650 1650);
FORCEPROP 1 LAST PATH I131
J 0
(-6650 1700);
DISPLAY 0.978723 (-6650 1700);
PAINT WHITE (-6650 1700);
DISPLAY INVISIBLE (-6650 1700);
FORCEPROP 2 LAST ROOM PVCCIN_CPU1_DECAP_VR
J 0
(-6650 1650);
PAINT ORANGE (-6650 1650);
DISPLAY INVISIBLE (-6650 1650);
FORCEADD CAP..1
(-7050 1550);
FORCEPROP 1 LAST LOCATION C8P13
J 0
(-7000 1650);
DISPLAY 0.617021 (-7000 1650);
PAINT AQUA (-7000 1650);
FORCEPROP 1 LAST PART_NUMBER C95333-006
R 1
J 0
(-7100 1375);
DISPLAY 0.617021 (-7100 1375);
PAINT BLUE (-7100 1375);
FORCEPROP 1 LAST VALUE 47UF
J 0
(-7000 1600);
DISPLAY 0.617021 (-7000 1600);
PAINT SKYBLUE (-7000 1600);
FORCEPROP 1 LAST TOLERANCE 20%
J 0
(-7000 1500);
DISPLAY 0.617021 (-7000 1500);
PAINT SKYBLUE (-7000 1500);
FORCEPROP 1 LAST PACK_TYPE 0805
J 0
(-7000 1400);
DISPLAY 0.617021 (-7000 1400);
PAINT SKYBLUE (-7000 1400);
FORCEPROP 1 LASTPIN (-7050 1450) $PN 2
J 0
(-7040 1430);
DISPLAY 0.617021 (-7040 1430);
PAINT GREEN (-7040 1430);
FORCEPROP 1 LASTPIN (-7050 1650) $PN 1
J 0
(-7040 1630);
DISPLAY 0.617021 (-7040 1630);
PAINT GREEN (-7040 1630);
FORCEPROP 1 LAST VOLTAGE 4V
J 0
(-7000 1550);
PAINT SKYBLUE (-7000 1550);
DISPLAY INVISIBLE (-7000 1550);
FORCEPROP 1 LAST MATERIAL X6S
J 0
(-7000 1450);
PAINT SKYBLUE (-7000 1450);
DISPLAY INVISIBLE (-7000 1450);
FORCEPROP 2 LAST BOM_COST PROC
J 0
(-7050 1550);
PAINT MONO (-7050 1550);
DISPLAY INVISIBLE (-7050 1550);
FORCEPROP 2 LAST CDS_LIB mstr_discrete
J 0
(-7050 1550);
PAINT ORANGE (-7050 1550);
DISPLAY INVISIBLE (-7050 1550);
FORCEPROP 2 LAST CDS_SEC 1
J 0
(-7000 1750);
DISPLAY 1.021277 (-7000 1750);
PAINT ORANGE (-7000 1750);
DISPLAY INVISIBLE (-7000 1750);
FORCEPROP 2 LAST $SEC 1
J 0
(-7000 1750);
DISPLAY 0.680851 (-7000 1750);
PAINT MONO (-7000 1750);
DISPLAY INVISIBLE (-7000 1750);
FORCEPROP 2 LAST CDS_LOCATION C8P13
J 0
(-7000 1650);
DISPLAY 0.617021 (-7000 1650);
PAINT AQUA (-7000 1650);
DISPLAY INVISIBLE (-7000 1650);
FORCEPROP 1 LAST PATH I132
J 0
(-7000 1700);
DISPLAY 0.978723 (-7000 1700);
PAINT WHITE (-7000 1700);
DISPLAY INVISIBLE (-7000 1700);
FORCEPROP 2 LAST ROOM PVCCIN_CPU1_DECAP_VR
J 0
(-7000 1650);
PAINT ORANGE (-7000 1650);
DISPLAY INVISIBLE (-7000 1650);
FORCEADD CAP..1
(-6350 900);
FORCEPROP 1 LAST LOCATION C8P17
J 0
(-6300 1000);
DISPLAY 0.617021 (-6300 1000);
PAINT AQUA (-6300 1000);
FORCEPROP 1 LAST PART_NUMBER C95333-006
R 1
J 0
(-6400 725);
DISPLAY 0.617021 (-6400 725);
PAINT BLUE (-6400 725);
FORCEPROP 1 LAST VALUE 47UF
J 0
(-6300 950);
DISPLAY 0.617021 (-6300 950);
PAINT SKYBLUE (-6300 950);
FORCEPROP 1 LAST TOLERANCE 20%
J 0
(-6300 850);
DISPLAY 0.617021 (-6300 850);
PAINT SKYBLUE (-6300 850);
FORCEPROP 1 LAST PACK_TYPE 0805
J 0
(-6330 725);
DISPLAY 0.617021 (-6330 725);
PAINT SKYBLUE (-6330 725);
FORCEPROP 1 LASTPIN (-6350 800) $PN 2
J 0
(-6340 780);
DISPLAY 0.617021 (-6340 780);
PAINT GREEN (-6340 780);
FORCEPROP 1 LASTPIN (-6350 1000) $PN 1
J 0
(-6340 980);
DISPLAY 0.617021 (-6340 980);
PAINT GREEN (-6340 980);
FORCEPROP 1 LAST VOLTAGE 4V
J 0
(-6300 900);
PAINT SKYBLUE (-6300 900);
DISPLAY INVISIBLE (-6300 900);
FORCEPROP 1 LAST MATERIAL X6S
J 0
(-6300 800);
PAINT SKYBLUE (-6300 800);
DISPLAY INVISIBLE (-6300 800);
FORCEPROP 2 LAST BOM_COST PROC
J 0
(-6350 900);
PAINT MONO (-6350 900);
DISPLAY INVISIBLE (-6350 900);
FORCEPROP 2 LAST CDS_LIB mstr_discrete
J 0
(-6350 900);
PAINT ORANGE (-6350 900);
DISPLAY INVISIBLE (-6350 900);
FORCEPROP 2 LAST CDS_SEC 1
J 0
(-6300 1100);
DISPLAY 1.021277 (-6300 1100);
PAINT ORANGE (-6300 1100);
DISPLAY INVISIBLE (-6300 1100);
FORCEPROP 2 LAST $SEC 1
J 0
(-6300 1100);
DISPLAY 0.680851 (-6300 1100);
PAINT MONO (-6300 1100);
DISPLAY INVISIBLE (-6300 1100);
FORCEPROP 2 LAST CDS_LOCATION C8P17
J 0
(-6300 1000);
DISPLAY 0.617021 (-6300 1000);
PAINT AQUA (-6300 1000);
DISPLAY INVISIBLE (-6300 1000);
FORCEPROP 1 LAST PATH I133
J 0
(-6300 1050);
DISPLAY 0.978723 (-6300 1050);
PAINT WHITE (-6300 1050);
DISPLAY INVISIBLE (-6300 1050);
FORCEPROP 2 LAST ROOM PVCCIN_CPU1_DECAP_VR
J 0
(-6300 1000);
PAINT ORANGE (-6300 1000);
DISPLAY INVISIBLE (-6300 1000);
FORCEADD GND..1
(-6350 575);
FORCEPROP 3 LASTPIN (-6350 625) SIG_NAME GND\g
J 0
(-6340 635);
DISPLAY 0.659574 (-6340 635);
PAINT MONO (-6340 635);
DISPLAY INVISIBLE (-6340 635);
FORCEPROP 1 LAST VOLTAGE 0
J 0
(-6350 575);
PAINT SKYBLUE (-6350 575);
DISPLAY INVISIBLE (-6350 575);
FORCEPROP 2 LAST CDS_LIB mstr_symbols
J 0
(-6350 575);
PAINT ORANGE (-6350 575);
DISPLAY INVISIBLE (-6350 575);
FORCEPROP 1 LAST SIZE 1B
J 0
(-6275 525);
DISPLAY 0.893617 (-6275 525);
PAINT GREEN (-6275 525);
DISPLAY INVISIBLE (-6275 525);
FORCEPROP 1 LAST BODY_TYPE PLUMBING
J 0
(-6395 532);
DISPLAY 0.340426 (-6395 532);
PAINT GREEN (-6395 532);
DISPLAY INVISIBLE (-6395 532);
FORCEPROP 1 LAST PATH I134
J 0
(-6275 575);
DISPLAY 0.872340 (-6275 575);
PAINT AQUA (-6275 575);
DISPLAY INVISIBLE (-6275 575);
FORCEPROP 2 LAST ROOM PVCCIN_CPU1_DECAP_VR
J 0
(-6900 650);
PAINT ORANGE (-6900 650);
DISPLAY INVISIBLE (-6900 650);
FORCEPROP 1 LAST HDL_POWER GND
J 0
(-6350 725);
DISPLAY 0.893617 (-6350 725);
PAINT GREEN (-6350 725);
DISPLAY INVISIBLE (-6350 725);
FORCEADD CAP..1
(-6700 900);
FORCEPROP 1 LAST LOCATION C8P21
J 0
(-6650 1000);
DISPLAY 0.617021 (-6650 1000);
PAINT AQUA (-6650 1000);
FORCEPROP 1 LAST PART_NUMBER C95333-006
R 1
J 0
(-6750 725);
DISPLAY 0.617021 (-6750 725);
PAINT BLUE (-6750 725);
FORCEPROP 1 LAST VALUE 47UF
J 0
(-6650 950);
DISPLAY 0.617021 (-6650 950);
PAINT SKYBLUE (-6650 950);
FORCEPROP 1 LAST TOLERANCE 20%
J 0
(-6650 850);
DISPLAY 0.617021 (-6650 850);
PAINT SKYBLUE (-6650 850);
FORCEPROP 1 LAST PACK_TYPE 0805
J 0
(-6690 720);
DISPLAY 0.617021 (-6690 720);
PAINT SKYBLUE (-6690 720);
FORCEPROP 1 LASTPIN (-6700 800) $PN 2
J 0
(-6690 780);
DISPLAY 0.617021 (-6690 780);
PAINT GREEN (-6690 780);
FORCEPROP 1 LASTPIN (-6700 1000) $PN 1
J 0
(-6690 980);
DISPLAY 0.617021 (-6690 980);
PAINT GREEN (-6690 980);
FORCEPROP 1 LAST VOLTAGE 4V
J 0
(-6650 900);
PAINT SKYBLUE (-6650 900);
DISPLAY INVISIBLE (-6650 900);
FORCEPROP 1 LAST MATERIAL X6S
J 0
(-6650 800);
PAINT SKYBLUE (-6650 800);
DISPLAY INVISIBLE (-6650 800);
FORCEPROP 2 LAST BOM_COST PROC
J 0
(-6700 900);
PAINT MONO (-6700 900);
DISPLAY INVISIBLE (-6700 900);
FORCEPROP 2 LAST CDS_LIB mstr_discrete
J 0
(-6700 900);
PAINT ORANGE (-6700 900);
DISPLAY INVISIBLE (-6700 900);
FORCEPROP 2 LAST CDS_SEC 1
J 0
(-6650 1100);
DISPLAY 1.021277 (-6650 1100);
PAINT ORANGE (-6650 1100);
DISPLAY INVISIBLE (-6650 1100);
FORCEPROP 2 LAST $SEC 1
J 0
(-6650 1100);
DISPLAY 0.680851 (-6650 1100);
PAINT MONO (-6650 1100);
DISPLAY INVISIBLE (-6650 1100);
FORCEPROP 2 LAST CDS_LOCATION C8P21
J 0
(-6650 1000);
DISPLAY 0.617021 (-6650 1000);
PAINT AQUA (-6650 1000);
DISPLAY INVISIBLE (-6650 1000);
FORCEPROP 1 LAST PATH I135
J 0
(-6650 1050);
DISPLAY 0.978723 (-6650 1050);
PAINT WHITE (-6650 1050);
DISPLAY INVISIBLE (-6650 1050);
FORCEPROP 2 LAST ROOM PVCCIN_CPU1_DECAP_VR
J 0
(-6650 1000);
PAINT ORANGE (-6650 1000);
DISPLAY INVISIBLE (-6650 1000);
FORCEADD CAP..1
(-7050 900);
FORCEPROP 1 LAST LOCATION C8P25
J 0
(-7000 1000);
DISPLAY 0.617021 (-7000 1000);
PAINT AQUA (-7000 1000);
FORCEPROP 1 LAST PART_NUMBER C95333-006
R 1
J 0
(-7100 725);
DISPLAY 0.617021 (-7100 725);
PAINT BLUE (-7100 725);
FORCEPROP 1 LAST VALUE 47UF
J 0
(-7000 950);
DISPLAY 0.617021 (-7000 950);
PAINT SKYBLUE (-7000 950);
FORCEPROP 1 LAST TOLERANCE 20%
J 0
(-7000 850);
DISPLAY 0.617021 (-7000 850);
PAINT SKYBLUE (-7000 850);
FORCEPROP 1 LAST PACK_TYPE 0805
J 0
(-7030 715);
DISPLAY 0.617021 (-7030 715);
PAINT SKYBLUE (-7030 715);
FORCEPROP 1 LASTPIN (-7050 800) $PN 2
J 0
(-7040 780);
DISPLAY 0.617021 (-7040 780);
PAINT GREEN (-7040 780);
FORCEPROP 1 LASTPIN (-7050 1000) $PN 1
J 0
(-7040 980);
DISPLAY 0.617021 (-7040 980);
PAINT GREEN (-7040 980);
FORCEPROP 1 LAST VOLTAGE 4V
J 0
(-7000 900);
PAINT SKYBLUE (-7000 900);
DISPLAY INVISIBLE (-7000 900);
FORCEPROP 1 LAST MATERIAL X6S
J 0
(-7000 800);
PAINT SKYBLUE (-7000 800);
DISPLAY INVISIBLE (-7000 800);
FORCEPROP 2 LAST BOM_COST PROC
J 0
(-7050 900);
PAINT MONO (-7050 900);
DISPLAY INVISIBLE (-7050 900);
FORCEPROP 2 LAST CDS_LIB mstr_discrete
J 0
(-7050 900);
PAINT ORANGE (-7050 900);
DISPLAY INVISIBLE (-7050 900);
FORCEPROP 2 LAST CDS_SEC 1
J 0
(-7000 1100);
DISPLAY 1.021277 (-7000 1100);
PAINT ORANGE (-7000 1100);
DISPLAY INVISIBLE (-7000 1100);
FORCEPROP 2 LAST $SEC 1
J 0
(-7000 1100);
DISPLAY 0.680851 (-7000 1100);
PAINT MONO (-7000 1100);
DISPLAY INVISIBLE (-7000 1100);
FORCEPROP 2 LAST CDS_LOCATION C8P25
J 0
(-7000 1000);
DISPLAY 0.617021 (-7000 1000);
PAINT AQUA (-7000 1000);
DISPLAY INVISIBLE (-7000 1000);
FORCEPROP 1 LAST PATH I136
J 0
(-7000 1050);
DISPLAY 0.978723 (-7000 1050);
PAINT WHITE (-7000 1050);
DISPLAY INVISIBLE (-7000 1050);
FORCEPROP 2 LAST ROOM PVCCIN_CPU1_DECAP_VR
J 0
(-7000 1000);
PAINT ORANGE (-7000 1000);
DISPLAY INVISIBLE (-7000 1000);
FORCEADD CAP..1
(-7375 1550);
FORCEPROP 1 LAST LOCATION C8P28
J 0
(-7325 1650);
DISPLAY 0.617021 (-7325 1650);
PAINT AQUA (-7325 1650);
FORCEPROP 1 LAST PART_NUMBER C95333-006
R 1
J 0
(-7425 1375);
DISPLAY 0.617021 (-7425 1375);
PAINT BLUE (-7425 1375);
FORCEPROP 1 LAST VALUE 47UF
J 0
(-7325 1600);
DISPLAY 0.617021 (-7325 1600);
PAINT SKYBLUE (-7325 1600);
FORCEPROP 1 LAST TOLERANCE 20%
J 0
(-7325 1500);
DISPLAY 0.617021 (-7325 1500);
PAINT SKYBLUE (-7325 1500);
FORCEPROP 1 LAST PACK_TYPE 0805
J 0
(-7325 1400);
DISPLAY 0.617021 (-7325 1400);
PAINT SKYBLUE (-7325 1400);
FORCEPROP 1 LASTPIN (-7375 1450) $PN 2
J 0
(-7365 1430);
DISPLAY 0.617021 (-7365 1430);
PAINT GREEN (-7365 1430);
FORCEPROP 1 LASTPIN (-7375 1650) $PN 1
J 0
(-7365 1630);
DISPLAY 0.617021 (-7365 1630);
PAINT GREEN (-7365 1630);
FORCEPROP 1 LAST VOLTAGE 4V
J 0
(-7325 1550);
PAINT SKYBLUE (-7325 1550);
DISPLAY INVISIBLE (-7325 1550);
FORCEPROP 1 LAST MATERIAL X6S
J 0
(-7325 1450);
PAINT SKYBLUE (-7325 1450);
DISPLAY INVISIBLE (-7325 1450);
FORCEPROP 2 LAST BOM_COST PROC
J 0
(-7375 1550);
PAINT MONO (-7375 1550);
DISPLAY INVISIBLE (-7375 1550);
FORCEPROP 2 LAST CDS_LIB mstr_discrete
J 0
(-7375 1550);
PAINT ORANGE (-7375 1550);
DISPLAY INVISIBLE (-7375 1550);
FORCEPROP 2 LAST CDS_SEC 1
J 0
(-7325 1750);
DISPLAY 1.021277 (-7325 1750);
PAINT ORANGE (-7325 1750);
DISPLAY INVISIBLE (-7325 1750);
FORCEPROP 2 LAST $SEC 1
J 0
(-7325 1750);
DISPLAY 0.680851 (-7325 1750);
PAINT MONO (-7325 1750);
DISPLAY INVISIBLE (-7325 1750);
FORCEPROP 2 LAST CDS_LOCATION C8P28
J 0
(-7325 1650);
DISPLAY 0.617021 (-7325 1650);
PAINT AQUA (-7325 1650);
DISPLAY INVISIBLE (-7325 1650);
FORCEPROP 1 LAST PATH I137
J 0
(-7325 1700);
DISPLAY 0.978723 (-7325 1700);
PAINT WHITE (-7325 1700);
DISPLAY INVISIBLE (-7325 1700);
FORCEPROP 2 LAST ROOM PVCCIN_CPU1_DECAP_VR
J 0
(-7300 1650);
PAINT ORANGE (-7300 1650);
DISPLAY INVISIBLE (-7300 1650);
FORCEADD CAP..1
(-7725 1550);
FORCEPROP 1 LAST LOCATION C8P11
J 0
(-7675 1650);
DISPLAY 0.617021 (-7675 1650);
PAINT AQUA (-7675 1650);
FORCEPROP 1 LAST PART_NUMBER C95333-006
R 1
J 0
(-7775 1375);
DISPLAY 0.617021 (-7775 1375);
PAINT BLUE (-7775 1375);
FORCEPROP 1 LAST VALUE 47UF
J 0
(-7675 1600);
DISPLAY 0.617021 (-7675 1600);
PAINT SKYBLUE (-7675 1600);
FORCEPROP 1 LAST TOLERANCE 20%
J 0
(-7675 1500);
DISPLAY 0.617021 (-7675 1500);
PAINT SKYBLUE (-7675 1500);
FORCEPROP 1 LAST PACK_TYPE 0805
J 0
(-7675 1400);
DISPLAY 0.617021 (-7675 1400);
PAINT SKYBLUE (-7675 1400);
FORCEPROP 1 LASTPIN (-7725 1450) $PN 2
J 0
(-7715 1430);
DISPLAY 0.617021 (-7715 1430);
PAINT GREEN (-7715 1430);
FORCEPROP 1 LASTPIN (-7725 1650) $PN 1
J 0
(-7715 1630);
DISPLAY 0.617021 (-7715 1630);
PAINT GREEN (-7715 1630);
FORCEPROP 1 LAST VOLTAGE 4V
J 0
(-7675 1550);
PAINT SKYBLUE (-7675 1550);
DISPLAY INVISIBLE (-7675 1550);
FORCEPROP 1 LAST MATERIAL X6S
J 0
(-7675 1450);
PAINT SKYBLUE (-7675 1450);
DISPLAY INVISIBLE (-7675 1450);
FORCEPROP 2 LAST CDS_LIB mstr_discrete
J 0
(-7725 1550);
PAINT ORANGE (-7725 1550);
DISPLAY INVISIBLE (-7725 1550);
FORCEPROP 2 LAST BOM_COST PROC
J 0
(-7725 1550);
PAINT MONO (-7725 1550);
DISPLAY INVISIBLE (-7725 1550);
FORCEPROP 2 LAST CDS_SEC 1
J 0
(-7675 1750);
DISPLAY 1.021277 (-7675 1750);
PAINT ORANGE (-7675 1750);
DISPLAY INVISIBLE (-7675 1750);
FORCEPROP 2 LAST $SEC 1
J 0
(-7675 1750);
DISPLAY 0.680851 (-7675 1750);
PAINT MONO (-7675 1750);
DISPLAY INVISIBLE (-7675 1750);
FORCEPROP 2 LAST CDS_LOCATION C8P11
J 0
(-7675 1650);
DISPLAY 0.617021 (-7675 1650);
PAINT AQUA (-7675 1650);
DISPLAY INVISIBLE (-7675 1650);
FORCEPROP 1 LAST PATH I139
J 0
(-7675 1700);
DISPLAY 0.978723 (-7675 1700);
PAINT WHITE (-7675 1700);
DISPLAY INVISIBLE (-7675 1700);
FORCEPROP 2 LAST ROOM PVCCIN_CPU1_DECAP_VR
J 0
(-7675 1650);
PAINT ORANGE (-7675 1650);
DISPLAY INVISIBLE (-7675 1650);
FORCEADD CAP..1
(-7375 900);
FORCEPROP 1 LAST LOCATION C8P27
J 0
(-7325 1000);
DISPLAY 0.617021 (-7325 1000);
PAINT AQUA (-7325 1000);
FORCEPROP 1 LAST PART_NUMBER C95333-006
R 1
J 0
(-7425 725);
DISPLAY 0.617021 (-7425 725);
PAINT BLUE (-7425 725);
FORCEPROP 1 LAST VALUE 47UF
J 0
(-7325 950);
DISPLAY 0.617021 (-7325 950);
PAINT SKYBLUE (-7325 950);
FORCEPROP 1 LAST TOLERANCE 20%
J 0
(-7325 850);
DISPLAY 0.617021 (-7325 850);
PAINT SKYBLUE (-7325 850);
FORCEPROP 1 LAST PACK_TYPE 0805
J 0
(-7365 710);
DISPLAY 0.617021 (-7365 710);
PAINT SKYBLUE (-7365 710);
FORCEPROP 1 LASTPIN (-7375 800) $PN 2
J 0
(-7365 780);
DISPLAY 0.617021 (-7365 780);
PAINT GREEN (-7365 780);
FORCEPROP 1 LASTPIN (-7375 1000) $PN 1
J 0
(-7365 980);
DISPLAY 0.617021 (-7365 980);
PAINT GREEN (-7365 980);
FORCEPROP 1 LAST VOLTAGE 4V
J 0
(-7325 900);
PAINT SKYBLUE (-7325 900);
DISPLAY INVISIBLE (-7325 900);
FORCEPROP 1 LAST MATERIAL X6S
J 0
(-7325 800);
PAINT SKYBLUE (-7325 800);
DISPLAY INVISIBLE (-7325 800);
FORCEPROP 2 LAST BOM_COST PROC
J 0
(-7375 900);
PAINT MONO (-7375 900);
DISPLAY INVISIBLE (-7375 900);
FORCEPROP 2 LAST CDS_LIB mstr_discrete
J 0
(-7375 900);
PAINT ORANGE (-7375 900);
DISPLAY INVISIBLE (-7375 900);
FORCEPROP 2 LAST CDS_SEC 1
J 0
(-7325 1100);
DISPLAY 1.021277 (-7325 1100);
PAINT ORANGE (-7325 1100);
DISPLAY INVISIBLE (-7325 1100);
FORCEPROP 2 LAST $SEC 1
J 0
(-7325 1100);
DISPLAY 0.680851 (-7325 1100);
PAINT MONO (-7325 1100);
DISPLAY INVISIBLE (-7325 1100);
FORCEPROP 2 LAST CDS_LOCATION C8P27
J 0
(-7325 1000);
DISPLAY 0.617021 (-7325 1000);
PAINT AQUA (-7325 1000);
DISPLAY INVISIBLE (-7325 1000);
FORCEPROP 1 LAST PATH I141
J 0
(-7325 1050);
DISPLAY 0.978723 (-7325 1050);
PAINT WHITE (-7325 1050);
DISPLAY INVISIBLE (-7325 1050);
FORCEPROP 2 LAST ROOM PVCCIN_CPU1_DECAP_VR
J 0
(-7300 1000);
PAINT ORANGE (-7300 1000);
DISPLAY INVISIBLE (-7300 1000);
FORCEADD PVCCIN_CPU1..1
(-5900 4725);
FORCEPROP 3 LASTPIN (-5900 4675) SIG_NAME PVCCIN_CPU1\g
J 0
(-5890 4685);
DISPLAY 0.659574 (-5890 4685);
PAINT MONO (-5890 4685);
DISPLAY INVISIBLE (-5890 4685);
FORCEPROP 1 LAST VOLTAGE 2.0V
J 0
(-5945 4682);
DISPLAY 0.340426 (-5945 4682);
PAINT SKYBLUE (-5945 4682);
DISPLAY INVISIBLE (-5945 4682);
FORCEPROP 2 LAST CDS_LIB mstr_symbols
J 0
(-5900 4725);
PAINT ORANGE (-5900 4725);
DISPLAY INVISIBLE (-5900 4725);
FORCEPROP 1 LAST BODY_TYPE PLUMBING
J 0
(-5945 4682);
DISPLAY 0.340426 (-5945 4682);
PAINT GREEN (-5945 4682);
DISPLAY INVISIBLE (-5945 4682);
FORCEPROP 1 LAST PATH I143
J 0
(-5850 4750);
DISPLAY 0.872340 (-5850 4750);
PAINT AQUA (-5850 4750);
DISPLAY INVISIBLE (-5850 4750);
FORCEPROP 2 LAST ROOM PVCCIN_CPU1_DECAP_VR
J 0
(-5650 4825);
PAINT ORANGE (-5650 4825);
DISPLAY INVISIBLE (-5650 4825);
FORCEPROP 1 LAST HDL_POWER PVCCIN_CPU1
J 1
(-5900 4775);
DISPLAY 0.872340 (-5900 4775);
PAINT GREEN (-5900 4775);
DISPLAY INVISIBLE (-5900 4775);
FORCEADD PVCCIN_CPU1..1
(-7675 4050);
FORCEPROP 3 LASTPIN (-7675 4000) SIG_NAME PVCCIN_CPU1\g
J 0
(-7665 4010);
DISPLAY 0.659574 (-7665 4010);
PAINT MONO (-7665 4010);
DISPLAY INVISIBLE (-7665 4010);
FORCEPROP 1 LAST VOLTAGE 2.0V
J 0
(-7720 4007);
DISPLAY 0.340426 (-7720 4007);
PAINT SKYBLUE (-7720 4007);
DISPLAY INVISIBLE (-7720 4007);
FORCEPROP 2 LAST CDS_LIB mstr_symbols
J 0
(-7675 4050);
PAINT ORANGE (-7675 4050);
DISPLAY INVISIBLE (-7675 4050);
FORCEPROP 1 LAST BODY_TYPE PLUMBING
J 0
(-7720 4007);
DISPLAY 0.340426 (-7720 4007);
PAINT GREEN (-7720 4007);
DISPLAY INVISIBLE (-7720 4007);
FORCEPROP 1 LAST PATH I144
J 0
(-7625 4075);
DISPLAY 0.872340 (-7625 4075);
PAINT AQUA (-7625 4075);
DISPLAY INVISIBLE (-7625 4075);
FORCEPROP 2 LAST ROOM PVCCIN_CPU1_DECAP_VR
J 0
(-7425 4150);
PAINT ORANGE (-7425 4150);
DISPLAY INVISIBLE (-7425 4150);
FORCEPROP 1 LAST HDL_POWER PVCCIN_CPU1
J 1
(-7675 4100);
DISPLAY 0.872340 (-7675 4100);
PAINT GREEN (-7675 4100);
DISPLAY INVISIBLE (-7675 4100);
FORCEADD PVCCIN_CPU1..1
(-7625 3425);
FORCEPROP 3 LASTPIN (-7625 3375) SIG_NAME PVCCIN_CPU1\g
J 0
(-7615 3385);
DISPLAY 0.659574 (-7615 3385);
PAINT MONO (-7615 3385);
DISPLAY INVISIBLE (-7615 3385);
FORCEPROP 1 LAST VOLTAGE 2.0V
J 0
(-7670 3382);
DISPLAY 0.340426 (-7670 3382);
PAINT SKYBLUE (-7670 3382);
DISPLAY INVISIBLE (-7670 3382);
FORCEPROP 2 LAST CDS_LIB mstr_symbols
J 0
(-7625 3425);
PAINT ORANGE (-7625 3425);
DISPLAY INVISIBLE (-7625 3425);
FORCEPROP 1 LAST BODY_TYPE PLUMBING
J 0
(-7670 3382);
DISPLAY 0.340426 (-7670 3382);
PAINT GREEN (-7670 3382);
DISPLAY INVISIBLE (-7670 3382);
FORCEPROP 1 LAST PATH I145
J 0
(-7575 3450);
DISPLAY 0.872340 (-7575 3450);
PAINT AQUA (-7575 3450);
DISPLAY INVISIBLE (-7575 3450);
FORCEPROP 2 LAST ROOM PVCCIN_CPU1_DECAP_VR
J 0
(-7375 3525);
PAINT ORANGE (-7375 3525);
DISPLAY INVISIBLE (-7375 3525);
FORCEPROP 1 LAST HDL_POWER PVCCIN_CPU1
J 1
(-7625 3475);
DISPLAY 0.872340 (-7625 3475);
PAINT GREEN (-7625 3475);
DISPLAY INVISIBLE (-7625 3475);
FORCEADD PVCCIN_CPU1..1
(-5875 4050);
FORCEPROP 3 LASTPIN (-5875 4000) SIG_NAME PVCCIN_CPU1\g
J 0
(-5865 4010);
DISPLAY 0.659574 (-5865 4010);
PAINT MONO (-5865 4010);
DISPLAY INVISIBLE (-5865 4010);
FORCEPROP 1 LAST VOLTAGE 2.0V
J 0
(-5920 4007);
DISPLAY 0.340426 (-5920 4007);
PAINT SKYBLUE (-5920 4007);
DISPLAY INVISIBLE (-5920 4007);
FORCEPROP 2 LAST CDS_LIB mstr_symbols
J 0
(-5875 4050);
PAINT ORANGE (-5875 4050);
DISPLAY INVISIBLE (-5875 4050);
FORCEPROP 1 LAST BODY_TYPE PLUMBING
J 0
(-5920 4007);
DISPLAY 0.340426 (-5920 4007);
PAINT GREEN (-5920 4007);
DISPLAY INVISIBLE (-5920 4007);
FORCEPROP 1 LAST PATH I146
J 0
(-5825 4075);
DISPLAY 0.872340 (-5825 4075);
PAINT AQUA (-5825 4075);
DISPLAY INVISIBLE (-5825 4075);
FORCEPROP 2 LAST ROOM PVCCIN_CPU1_DECAP_VR
J 0
(-5625 4150);
PAINT ORANGE (-5625 4150);
DISPLAY INVISIBLE (-5625 4150);
FORCEPROP 1 LAST HDL_POWER PVCCIN_CPU1
J 1
(-5875 4100);
DISPLAY 0.872340 (-5875 4100);
PAINT GREEN (-5875 4100);
DISPLAY INVISIBLE (-5875 4100);
FORCEADD PVCCIN_CPU1..1
(-5850 3425);
FORCEPROP 3 LASTPIN (-5850 3375) SIG_NAME PVCCIN_CPU1\g
J 0
(-5840 3385);
DISPLAY 0.659574 (-5840 3385);
PAINT MONO (-5840 3385);
DISPLAY INVISIBLE (-5840 3385);
FORCEPROP 1 LAST VOLTAGE 2.0V
J 0
(-5895 3382);
DISPLAY 0.340426 (-5895 3382);
PAINT SKYBLUE (-5895 3382);
DISPLAY INVISIBLE (-5895 3382);
FORCEPROP 2 LAST CDS_LIB mstr_symbols
J 0
(-5850 3425);
PAINT ORANGE (-5850 3425);
DISPLAY INVISIBLE (-5850 3425);
FORCEPROP 1 LAST BODY_TYPE PLUMBING
J 0
(-5895 3382);
DISPLAY 0.340426 (-5895 3382);
PAINT GREEN (-5895 3382);
DISPLAY INVISIBLE (-5895 3382);
FORCEPROP 1 LAST PATH I147
J 0
(-5800 3450);
DISPLAY 0.872340 (-5800 3450);
PAINT AQUA (-5800 3450);
DISPLAY INVISIBLE (-5800 3450);
FORCEPROP 2 LAST ROOM PVCCIN_CPU1_DECAP_VR
J 0
(-5600 3525);
PAINT ORANGE (-5600 3525);
DISPLAY INVISIBLE (-5600 3525);
FORCEPROP 1 LAST HDL_POWER PVCCIN_CPU1
J 1
(-5850 3475);
DISPLAY 0.872340 (-5850 3475);
PAINT GREEN (-5850 3475);
DISPLAY INVISIBLE (-5850 3475);
FORCEADD CAP_A..1
(-2450 3750);
FORCEPROP 1 LAST LOCATION C3D9
J 0
(-2400 3850);
DISPLAY 0.617021 (-2400 3850);
PAINT AQUA (-2400 3850);
FORCEPROP 1 LAST PART_NUMBER E15431-004
J 0
(-2400 3600);
DISPLAY 0.617021 (-2400 3600);
PAINT BLUE (-2400 3600);
FORCEPROP 1 LAST VALUE 22.0UF
J 0
(-2400 3800);
DISPLAY 0.617021 (-2400 3800);
PAINT SKYBLUE (-2400 3800);
FORCEPROP 1 LAST TOLERANCE 20%
J 0
(-2400 3700);
DISPLAY 0.617021 (-2400 3700);
PAINT SKYBLUE (-2400 3700);
FORCEPROP 1 LAST PACK_TYPE 0603V
J 0
(-2400 3550);
DISPLAY 0.617021 (-2400 3550);
PAINT SKYBLUE (-2400 3550);
FORCEPROP 1 LAST VOLTAGE 4V
J 0
(-2400 3750);
DISPLAY 0.617021 (-2400 3750);
PAINT SKYBLUE (-2400 3750);
FORCEPROP 1 LAST MATERIAL X6S
J 0
(-2400 3650);
DISPLAY 0.617021 (-2400 3650);
PAINT SKYBLUE (-2400 3650);
FORCEPROP 1 LASTPIN (-2450 3850) $PN 1
J 0
(-2440 3830);
DISPLAY 0.617021 (-2440 3830);
PAINT GREEN (-2440 3830);
FORCEPROP 1 LASTPIN (-2450 3650) $PN 2
J 0
(-2440 3630);
DISPLAY 0.617021 (-2440 3630);
PAINT GREEN (-2440 3630);
FORCEPROP 2 LAST CDS_LOCATION C3D9
J 0
(-2400 3850);
DISPLAY 0.617021 (-2400 3850);
PAINT AQUA (-2400 3850);
DISPLAY INVISIBLE (-2400 3850);
FORCEPROP 2 LAST BOM_COST PROC
J 0
(-2450 3750);
PAINT MONO (-2450 3750);
DISPLAY INVISIBLE (-2450 3750);
FORCEPROP 2 LAST CDS_LIB dev_discrete
J 0
(-2450 3750);
PAINT ORANGE (-2450 3750);
DISPLAY INVISIBLE (-2450 3750);
FORCEPROP 2 LAST CDS_SEC 1
J 0
(-2400 3950);
PAINT MONO (-2400 3950);
DISPLAY INVISIBLE (-2400 3950);
FORCEPROP 2 LAST $SEC 1
J 0
(-2400 3950);
PAINT MONO (-2400 3950);
DISPLAY INVISIBLE (-2400 3950);
FORCEPROP 1 LAST PATH I15
J 0
(-2400 3900);
DISPLAY 0.978723 (-2400 3900);
PAINT WHITE (-2400 3900);
DISPLAY INVISIBLE (-2400 3900);
FORCEPROP 2 LAST ROOM PVCCIN_CPU1_DECAP_VR
J 0
(-2400 3850);
PAINT ORANGE (-2400 3850);
DISPLAY INVISIBLE (-2400 3850);
FORCEADD PVCCIN_CPU1..1
(-5975 2475);
FORCEPROP 3 LASTPIN (-5975 2425) SIG_NAME PVCCIN_CPU1\g
J 0
(-5965 2435);
DISPLAY 0.659574 (-5965 2435);
PAINT MONO (-5965 2435);
DISPLAY INVISIBLE (-5965 2435);
FORCEPROP 1 LAST VOLTAGE 2.0V
J 0
(-6020 2432);
DISPLAY 0.340426 (-6020 2432);
PAINT SKYBLUE (-6020 2432);
DISPLAY INVISIBLE (-6020 2432);
FORCEPROP 2 LAST CDS_LIB mstr_symbols
J 0
(-5975 2475);
PAINT ORANGE (-5975 2475);
DISPLAY INVISIBLE (-5975 2475);
FORCEPROP 1 LAST BODY_TYPE PLUMBING
J 0
(-6020 2432);
DISPLAY 0.340426 (-6020 2432);
PAINT GREEN (-6020 2432);
DISPLAY INVISIBLE (-6020 2432);
FORCEPROP 1 LAST PATH I153
J 0
(-5925 2500);
DISPLAY 0.872340 (-5925 2500);
PAINT AQUA (-5925 2500);
DISPLAY INVISIBLE (-5925 2500);
FORCEPROP 2 LAST ROOM PVCCIN_CPU1_DECAP_VR
J 0
(-5725 2575);
PAINT ORANGE (-5725 2575);
DISPLAY INVISIBLE (-5725 2575);
FORCEPROP 1 LAST HDL_POWER PVCCIN_CPU1
J 1
(-5975 2525);
DISPLAY 0.872340 (-5975 2525);
PAINT GREEN (-5975 2525);
DISPLAY INVISIBLE (-5975 2525);
FORCEADD PVCCIN_CPU1..1
(-7725 2475);
FORCEPROP 3 LASTPIN (-7725 2425) SIG_NAME PVCCIN_CPU1\g
J 0
(-7715 2435);
DISPLAY 0.659574 (-7715 2435);
PAINT MONO (-7715 2435);
DISPLAY INVISIBLE (-7715 2435);
FORCEPROP 1 LAST VOLTAGE 2.0V
J 0
(-7770 2432);
DISPLAY 0.340426 (-7770 2432);
PAINT SKYBLUE (-7770 2432);
DISPLAY INVISIBLE (-7770 2432);
FORCEPROP 2 LAST CDS_LIB mstr_symbols
J 0
(-7725 2475);
PAINT ORANGE (-7725 2475);
DISPLAY INVISIBLE (-7725 2475);
FORCEPROP 1 LAST BODY_TYPE PLUMBING
J 0
(-7770 2432);
DISPLAY 0.340426 (-7770 2432);
PAINT GREEN (-7770 2432);
DISPLAY INVISIBLE (-7770 2432);
FORCEPROP 1 LAST PATH I154
J 0
(-7675 2500);
DISPLAY 0.872340 (-7675 2500);
PAINT AQUA (-7675 2500);
DISPLAY INVISIBLE (-7675 2500);
FORCEPROP 2 LAST ROOM PVCCIN_CPU1_DECAP_VR
J 0
(-7475 2575);
PAINT ORANGE (-7475 2575);
DISPLAY INVISIBLE (-7475 2575);
FORCEPROP 1 LAST HDL_POWER PVCCIN_CPU1
J 1
(-7725 2525);
DISPLAY 0.872340 (-7725 2525);
PAINT GREEN (-7725 2525);
DISPLAY INVISIBLE (-7725 2525);
FORCEADD PVCCIN_CPU1..1
(-7725 1825);
FORCEPROP 3 LASTPIN (-7725 1775) SIG_NAME PVCCIN_CPU1\g
J 0
(-7715 1785);
DISPLAY 0.659574 (-7715 1785);
PAINT MONO (-7715 1785);
DISPLAY INVISIBLE (-7715 1785);
FORCEPROP 1 LAST VOLTAGE 2.0V
J 0
(-7770 1782);
DISPLAY 0.340426 (-7770 1782);
PAINT SKYBLUE (-7770 1782);
DISPLAY INVISIBLE (-7770 1782);
FORCEPROP 2 LAST CDS_LIB mstr_symbols
J 0
(-7725 1825);
PAINT ORANGE (-7725 1825);
DISPLAY INVISIBLE (-7725 1825);
FORCEPROP 1 LAST BODY_TYPE PLUMBING
J 0
(-7770 1782);
DISPLAY 0.340426 (-7770 1782);
PAINT GREEN (-7770 1782);
DISPLAY INVISIBLE (-7770 1782);
FORCEPROP 1 LAST PATH I155
J 0
(-7675 1850);
DISPLAY 0.872340 (-7675 1850);
PAINT AQUA (-7675 1850);
DISPLAY INVISIBLE (-7675 1850);
FORCEPROP 2 LAST ROOM PVCCIN_CPU1_DECAP_VR
J 0
(-7475 1925);
PAINT ORANGE (-7475 1925);
DISPLAY INVISIBLE (-7475 1925);
FORCEPROP 1 LAST HDL_POWER PVCCIN_CPU1
J 1
(-7725 1875);
DISPLAY 0.872340 (-7725 1875);
PAINT GREEN (-7725 1875);
DISPLAY INVISIBLE (-7725 1875);
FORCEADD PVCCIN_CPU1..1
(-5975 1825);
FORCEPROP 3 LASTPIN (-5975 1775) SIG_NAME PVCCIN_CPU1\g
J 0
(-5965 1785);
DISPLAY 0.659574 (-5965 1785);
PAINT MONO (-5965 1785);
DISPLAY INVISIBLE (-5965 1785);
FORCEPROP 1 LAST VOLTAGE 2.0V
J 0
(-6020 1782);
DISPLAY 0.340426 (-6020 1782);
PAINT SKYBLUE (-6020 1782);
DISPLAY INVISIBLE (-6020 1782);
FORCEPROP 2 LAST CDS_LIB mstr_symbols
J 0
(-5975 1825);
PAINT ORANGE (-5975 1825);
DISPLAY INVISIBLE (-5975 1825);
FORCEPROP 1 LAST BODY_TYPE PLUMBING
J 0
(-6020 1782);
DISPLAY 0.340426 (-6020 1782);
PAINT GREEN (-6020 1782);
DISPLAY INVISIBLE (-6020 1782);
FORCEPROP 1 LAST PATH I156
J 0
(-5925 1850);
DISPLAY 0.872340 (-5925 1850);
PAINT AQUA (-5925 1850);
DISPLAY INVISIBLE (-5925 1850);
FORCEPROP 2 LAST ROOM PVCCIN_CPU1_DECAP_VR
J 0
(-5725 1925);
PAINT ORANGE (-5725 1925);
DISPLAY INVISIBLE (-5725 1925);
FORCEPROP 1 LAST HDL_POWER PVCCIN_CPU1
J 1
(-5975 1875);
DISPLAY 0.872340 (-5975 1875);
PAINT GREEN (-5975 1875);
DISPLAY INVISIBLE (-5975 1875);
FORCEADD PVCCIN_CPU1..1
(-5950 1150);
FORCEPROP 3 LASTPIN (-5950 1100) SIG_NAME PVCCIN_CPU1\g
J 0
(-5940 1110);
DISPLAY 0.659574 (-5940 1110);
PAINT MONO (-5940 1110);
DISPLAY INVISIBLE (-5940 1110);
FORCEPROP 1 LAST VOLTAGE 2.0V
J 0
(-5995 1107);
DISPLAY 0.340426 (-5995 1107);
PAINT SKYBLUE (-5995 1107);
DISPLAY INVISIBLE (-5995 1107);
FORCEPROP 2 LAST CDS_LIB mstr_symbols
J 0
(-5950 1150);
PAINT ORANGE (-5950 1150);
DISPLAY INVISIBLE (-5950 1150);
FORCEPROP 1 LAST BODY_TYPE PLUMBING
J 0
(-5995 1107);
DISPLAY 0.340426 (-5995 1107);
PAINT GREEN (-5995 1107);
DISPLAY INVISIBLE (-5995 1107);
FORCEPROP 1 LAST PATH I157
J 0
(-5900 1175);
DISPLAY 0.872340 (-5900 1175);
PAINT AQUA (-5900 1175);
DISPLAY INVISIBLE (-5900 1175);
FORCEPROP 2 LAST ROOM PVCCIN_CPU1_DECAP_VR
J 0
(-5700 1250);
PAINT ORANGE (-5700 1250);
DISPLAY INVISIBLE (-5700 1250);
FORCEPROP 1 LAST HDL_POWER PVCCIN_CPU1
J 1
(-5950 1200);
DISPLAY 0.872340 (-5950 1200);
PAINT GREEN (-5950 1200);
DISPLAY INVISIBLE (-5950 1200);
FORCEADD PVCCIN_CPU1..1
(-7725 1175);
FORCEPROP 3 LASTPIN (-7725 1125) SIG_NAME PVCCIN_CPU1\g
J 0
(-7715 1135);
DISPLAY 0.659574 (-7715 1135);
PAINT MONO (-7715 1135);
DISPLAY INVISIBLE (-7715 1135);
FORCEPROP 1 LAST VOLTAGE 2.0V
J 0
(-7770 1132);
DISPLAY 0.340426 (-7770 1132);
PAINT SKYBLUE (-7770 1132);
DISPLAY INVISIBLE (-7770 1132);
FORCEPROP 2 LAST CDS_LIB mstr_symbols
J 0
(-7725 1175);
PAINT ORANGE (-7725 1175);
DISPLAY INVISIBLE (-7725 1175);
FORCEPROP 1 LAST BODY_TYPE PLUMBING
J 0
(-7770 1132);
DISPLAY 0.340426 (-7770 1132);
PAINT GREEN (-7770 1132);
DISPLAY INVISIBLE (-7770 1132);
FORCEPROP 1 LAST PATH I158
J 0
(-7675 1200);
DISPLAY 0.872340 (-7675 1200);
PAINT AQUA (-7675 1200);
DISPLAY INVISIBLE (-7675 1200);
FORCEPROP 2 LAST ROOM PVCCIN_CPU1_DECAP_VR
J 0
(-7475 1275);
PAINT ORANGE (-7475 1275);
DISPLAY INVISIBLE (-7475 1275);
FORCEPROP 1 LAST HDL_POWER PVCCIN_CPU1
J 1
(-7725 1225);
DISPLAY 0.872340 (-7725 1225);
PAINT GREEN (-7725 1225);
DISPLAY INVISIBLE (-7725 1225);
FORCEADD CAP_A..1
(-4325 4425);
FORCEPROP 1 LAST LOCATION C2D15
J 0
(-4275 4525);
DISPLAY 0.617021 (-4275 4525);
PAINT AQUA (-4275 4525);
FORCEPROP 1 LAST PART_NUMBER E15431-004
J 0
(-4275 4275);
DISPLAY 0.617021 (-4275 4275);
PAINT BLUE (-4275 4275);
FORCEPROP 1 LAST VALUE 22.0UF
J 0
(-4275 4475);
DISPLAY 0.617021 (-4275 4475);
PAINT SKYBLUE (-4275 4475);
FORCEPROP 1 LAST TOLERANCE 20%
J 0
(-4275 4375);
DISPLAY 0.617021 (-4275 4375);
PAINT SKYBLUE (-4275 4375);
FORCEPROP 1 LAST PACK_TYPE 0603V
J 0
(-4275 4225);
DISPLAY 0.617021 (-4275 4225);
PAINT SKYBLUE (-4275 4225);
FORCEPROP 1 LAST VOLTAGE 4V
J 0
(-4275 4425);
DISPLAY 0.617021 (-4275 4425);
PAINT SKYBLUE (-4275 4425);
FORCEPROP 1 LAST MATERIAL X6S
J 0
(-4275 4325);
DISPLAY 0.617021 (-4275 4325);
PAINT SKYBLUE (-4275 4325);
FORCEPROP 1 LASTPIN (-4325 4525) $PN 1
J 0
(-4315 4505);
DISPLAY 0.617021 (-4315 4505);
PAINT ORANGE (-4315 4505);
FORCEPROP 1 LASTPIN (-4325 4325) $PN 2
J 0
(-4315 4305);
DISPLAY 0.617021 (-4315 4305);
PAINT ORANGE (-4315 4305);
FORCEPROP 2 LAST CDS_LOCATION C2D15
J 0
(-4275 4525);
DISPLAY 0.617021 (-4275 4525);
PAINT AQUA (-4275 4525);
DISPLAY INVISIBLE (-4275 4525);
FORCEPROP 2 LAST BOM_COST PROC
J 0
(-4325 4425);
PAINT MONO (-4325 4425);
DISPLAY INVISIBLE (-4325 4425);
FORCEPROP 2 LAST CDS_LIB dev_discrete
J 0
(-4325 4425);
PAINT ORANGE (-4325 4425);
DISPLAY INVISIBLE (-4325 4425);
FORCEPROP 2 LAST CDS_SEC 1
J 0
(-4275 4625);
PAINT MONO (-4275 4625);
DISPLAY INVISIBLE (-4275 4625);
FORCEPROP 2 LAST $SEC 1
J 0
(-4275 4625);
PAINT MONO (-4275 4625);
DISPLAY INVISIBLE (-4275 4625);
FORCEPROP 1 LAST PATH I159
J 0
(-4275 4575);
DISPLAY 0.978723 (-4275 4575);
PAINT WHITE (-4275 4575);
DISPLAY INVISIBLE (-4275 4575);
FORCEPROP 2 LAST ROOM PVCCIN_CPU1_DECAP_VR
J 0
(-4275 4525);
PAINT ORANGE (-4275 4525);
DISPLAY INVISIBLE (-4275 4525);
FORCEADD GND..1
(-2450 3425);
FORCEPROP 3 LASTPIN (-2450 3475) SIG_NAME GND\g
J 0
(-2440 3485);
DISPLAY 0.659574 (-2440 3485);
PAINT MONO (-2440 3485);
DISPLAY INVISIBLE (-2440 3485);
FORCEPROP 1 LAST VOLTAGE 0
J 0
(-2450 3425);
PAINT SKYBLUE (-2450 3425);
DISPLAY INVISIBLE (-2450 3425);
FORCEPROP 2 LAST CDS_LIB mstr_symbols
J 0
(-2450 3425);
PAINT ORANGE (-2450 3425);
DISPLAY INVISIBLE (-2450 3425);
FORCEPROP 1 LAST SIZE 1B
J 0
(-2375 3375);
DISPLAY 0.893617 (-2375 3375);
PAINT GREEN (-2375 3375);
DISPLAY INVISIBLE (-2375 3375);
FORCEPROP 1 LAST BODY_TYPE PLUMBING
J 0
(-2495 3382);
DISPLAY 0.340426 (-2495 3382);
PAINT GREEN (-2495 3382);
DISPLAY INVISIBLE (-2495 3382);
FORCEPROP 1 LAST PATH I16
J 0
(-2375 3425);
DISPLAY 0.872340 (-2375 3425);
PAINT AQUA (-2375 3425);
DISPLAY INVISIBLE (-2375 3425);
FORCEPROP 2 LAST ROOM PVCCIN_CPU1_DECAP_VR
J 0
(-3000 3500);
PAINT ORANGE (-3000 3500);
DISPLAY INVISIBLE (-3000 3500);
FORCEPROP 1 LAST HDL_POWER GND
J 0
(-2450 3575);
DISPLAY 0.893617 (-2450 3575);
PAINT GREEN (-2450 3575);
DISPLAY INVISIBLE (-2450 3575);
FORCEADD CAP_A..1
(-4325 3750);
FORCEPROP 1 LAST LOCATION C2D38
J 0
(-4275 3850);
DISPLAY 0.617021 (-4275 3850);
PAINT AQUA (-4275 3850);
FORCEPROP 1 LAST PART_NUMBER E15431-004
J 0
(-4275 3600);
DISPLAY 0.617021 (-4275 3600);
PAINT BLUE (-4275 3600);
FORCEPROP 1 LAST VALUE 22.0UF
J 0
(-4275 3800);
DISPLAY 0.617021 (-4275 3800);
PAINT SKYBLUE (-4275 3800);
FORCEPROP 1 LAST TOLERANCE 20%
J 0
(-4275 3700);
DISPLAY 0.617021 (-4275 3700);
PAINT SKYBLUE (-4275 3700);
FORCEPROP 1 LAST PACK_TYPE 0603V
J 0
(-4275 3550);
DISPLAY 0.617021 (-4275 3550);
PAINT SKYBLUE (-4275 3550);
FORCEPROP 1 LAST VOLTAGE 4V
J 0
(-4275 3750);
DISPLAY 0.617021 (-4275 3750);
PAINT SKYBLUE (-4275 3750);
FORCEPROP 1 LAST MATERIAL X6S
J 0
(-4275 3650);
DISPLAY 0.617021 (-4275 3650);
PAINT SKYBLUE (-4275 3650);
FORCEPROP 1 LASTPIN (-4325 3850) $PN 1
J 0
(-4315 3830);
DISPLAY 0.617021 (-4315 3830);
PAINT ORANGE (-4315 3830);
FORCEPROP 1 LASTPIN (-4325 3650) $PN 2
J 0
(-4315 3630);
DISPLAY 0.617021 (-4315 3630);
PAINT ORANGE (-4315 3630);
FORCEPROP 2 LAST CDS_LOCATION C2D38
J 0
(-4275 3850);
DISPLAY 0.617021 (-4275 3850);
PAINT AQUA (-4275 3850);
DISPLAY INVISIBLE (-4275 3850);
FORCEPROP 2 LAST BOM_COST PROC
J 0
(-4325 3750);
PAINT MONO (-4325 3750);
DISPLAY INVISIBLE (-4325 3750);
FORCEPROP 2 LAST CDS_LIB dev_discrete
J 0
(-4325 3750);
PAINT ORANGE (-4325 3750);
DISPLAY INVISIBLE (-4325 3750);
FORCEPROP 2 LAST CDS_SEC 1
J 0
(-4275 3950);
PAINT MONO (-4275 3950);
DISPLAY INVISIBLE (-4275 3950);
FORCEPROP 2 LAST $SEC 1
J 0
(-4275 3950);
PAINT MONO (-4275 3950);
DISPLAY INVISIBLE (-4275 3950);
FORCEPROP 1 LAST PATH I160
J 0
(-4275 3900);
DISPLAY 0.978723 (-4275 3900);
PAINT WHITE (-4275 3900);
DISPLAY INVISIBLE (-4275 3900);
FORCEPROP 2 LAST ROOM PVCCIN_CPU1_DECAP_VR
J 0
(-4275 3850);
PAINT ORANGE (-4275 3850);
DISPLAY INVISIBLE (-4275 3850);
FORCEADD CAP_A..1
(-4325 3150);
FORCEPROP 1 LAST LOCATION C2D35
J 0
(-4275 3250);
DISPLAY 0.617021 (-4275 3250);
PAINT AQUA (-4275 3250);
FORCEPROP 1 LAST PART_NUMBER E15431-004
J 0
(-4275 3000);
DISPLAY 0.617021 (-4275 3000);
PAINT BLUE (-4275 3000);
FORCEPROP 1 LAST VALUE 22.0UF
J 0
(-4275 3200);
DISPLAY 0.617021 (-4275 3200);
PAINT SKYBLUE (-4275 3200);
FORCEPROP 1 LAST TOLERANCE 20%
J 0
(-4275 3100);
DISPLAY 0.617021 (-4275 3100);
PAINT SKYBLUE (-4275 3100);
FORCEPROP 1 LAST PACK_TYPE 0603V
J 0
(-4275 2950);
DISPLAY 0.617021 (-4275 2950);
PAINT SKYBLUE (-4275 2950);
FORCEPROP 1 LAST VOLTAGE 4V
J 0
(-4275 3150);
DISPLAY 0.617021 (-4275 3150);
PAINT SKYBLUE (-4275 3150);
FORCEPROP 1 LAST MATERIAL X6S
J 0
(-4275 3050);
DISPLAY 0.617021 (-4275 3050);
PAINT SKYBLUE (-4275 3050);
FORCEPROP 1 LASTPIN (-4325 3250) $PN 1
J 0
(-4315 3230);
DISPLAY 0.617021 (-4315 3230);
PAINT ORANGE (-4315 3230);
FORCEPROP 1 LASTPIN (-4325 3050) $PN 2
J 0
(-4315 3030);
DISPLAY 0.617021 (-4315 3030);
PAINT ORANGE (-4315 3030);
FORCEPROP 2 LAST CDS_LOCATION C2D35
J 0
(-4275 3250);
DISPLAY 0.617021 (-4275 3250);
PAINT AQUA (-4275 3250);
DISPLAY INVISIBLE (-4275 3250);
FORCEPROP 2 LAST BOM_COST PROC
J 0
(-4325 3150);
PAINT MONO (-4325 3150);
DISPLAY INVISIBLE (-4325 3150);
FORCEPROP 2 LAST CDS_LIB dev_discrete
J 0
(-4325 3150);
PAINT ORANGE (-4325 3150);
DISPLAY INVISIBLE (-4325 3150);
FORCEPROP 2 LAST CDS_SEC 1
J 0
(-4275 3350);
PAINT MONO (-4275 3350);
DISPLAY INVISIBLE (-4275 3350);
FORCEPROP 2 LAST $SEC 1
J 0
(-4275 3350);
PAINT MONO (-4275 3350);
DISPLAY INVISIBLE (-4275 3350);
FORCEPROP 1 LAST PATH I161
J 0
(-4275 3300);
DISPLAY 0.978723 (-4275 3300);
PAINT WHITE (-4275 3300);
DISPLAY INVISIBLE (-4275 3300);
FORCEPROP 2 LAST ROOM PVCCIN_CPU1_DECAP_VR
J 0
(-4275 3250);
PAINT ORANGE (-4275 3250);
DISPLAY INVISIBLE (-4275 3250);
FORCEADD VCC_CORE..1
(-4000 4725);
FORCEPROP 3 LASTPIN (-4000 4675) SIG_NAME PVCCMCP_CPU1\g
J 0
(-3990 4685);
DISPLAY 0.659574 (-3990 4685);
PAINT MONO (-3990 4685);
DISPLAY INVISIBLE (-3990 4685);
FORCEPROP 1 LAST HDL_POWER PVCCMCP_CPU1
J 1
(-4000 4775);
DISPLAY 0.617021 (-4000 4775);
PAINT GREEN (-4000 4775);
FORCEPROP 2 LAST CDS_LIB mstr_symbols
J 0
(-4000 4725);
PAINT ORANGE (-4000 4725);
DISPLAY INVISIBLE (-4000 4725);
FORCEPROP 1 LAST PATH I162
J 0
(-3950 4750);
DISPLAY 0.872340 (-3950 4750);
PAINT AQUA (-3950 4750);
DISPLAY INVISIBLE (-3950 4750);
FORCEADD VCC_CORE..1
(-4775 2475);
FORCEPROP 3 LASTPIN (-4775 2425) SIG_NAME PVCCMCP_CPU1\g
J 0
(-4765 2435);
DISPLAY 0.659574 (-4765 2435);
PAINT MONO (-4765 2435);
DISPLAY INVISIBLE (-4765 2435);
FORCEPROP 1 LAST HDL_POWER PVCCMCP_CPU1
J 1
(-4775 2525);
DISPLAY 0.617021 (-4775 2525);
PAINT GREEN (-4775 2525);
FORCEPROP 2 LAST CDS_LIB mstr_symbols
J 0
(-4775 2475);
PAINT ORANGE (-4775 2475);
DISPLAY INVISIBLE (-4775 2475);
FORCEPROP 1 LAST PATH I163
J 0
(-4725 2500);
DISPLAY 0.872340 (-4725 2500);
PAINT AQUA (-4725 2500);
DISPLAY INVISIBLE (-4725 2500);
FORCEADD CAP_A..1
(-4000 4450);
FORCEPROP 1 LAST LOCATION C3D7
J 0
(-3950 4550);
DISPLAY 0.617021 (-3950 4550);
PAINT AQUA (-3950 4550);
FORCEPROP 1 LAST PART_NUMBER E15431-004
J 0
(-3950 4300);
DISPLAY 0.617021 (-3950 4300);
PAINT BLUE (-3950 4300);
FORCEPROP 1 LAST VALUE 22.0UF
J 0
(-3950 4500);
DISPLAY 0.617021 (-3950 4500);
PAINT SKYBLUE (-3950 4500);
FORCEPROP 1 LAST TOLERANCE 20%
J 0
(-3950 4400);
DISPLAY 0.617021 (-3950 4400);
PAINT SKYBLUE (-3950 4400);
FORCEPROP 1 LAST PACK_TYPE 0603V
J 0
(-3950 4250);
DISPLAY 0.617021 (-3950 4250);
PAINT SKYBLUE (-3950 4250);
FORCEPROP 1 LAST VOLTAGE 4V
J 0
(-3950 4450);
DISPLAY 0.617021 (-3950 4450);
PAINT SKYBLUE (-3950 4450);
FORCEPROP 1 LAST MATERIAL X6S
J 0
(-3950 4350);
DISPLAY 0.617021 (-3950 4350);
PAINT SKYBLUE (-3950 4350);
FORCEPROP 1 LASTPIN (-4000 4550) $PN 1
J 0
(-3990 4530);
DISPLAY 0.617021 (-3990 4530);
PAINT ORANGE (-3990 4530);
FORCEPROP 1 LASTPIN (-4000 4350) $PN 2
J 0
(-3990 4330);
DISPLAY 0.617021 (-3990 4330);
PAINT ORANGE (-3990 4330);
FORCEPROP 2 LAST CDS_LOCATION C3D7
J 0
(-3950 4550);
DISPLAY 0.617021 (-3950 4550);
PAINT AQUA (-3950 4550);
DISPLAY INVISIBLE (-3950 4550);
FORCEPROP 2 LAST CDS_LIB dev_discrete
J 0
(-4000 4450);
PAINT ORANGE (-4000 4450);
DISPLAY INVISIBLE (-4000 4450);
FORCEPROP 2 LAST CDS_SEC 1
J 0
(-3950 4650);
PAINT MONO (-3950 4650);
DISPLAY INVISIBLE (-3950 4650);
FORCEPROP 2 LAST $SEC 1
J 0
(-3950 4650);
PAINT MONO (-3950 4650);
DISPLAY INVISIBLE (-3950 4650);
FORCEPROP 1 LAST PATH I164
J 0
(-3950 4600);
DISPLAY 0.978723 (-3950 4600);
PAINT WHITE (-3950 4600);
DISPLAY INVISIBLE (-3950 4600);
FORCEPROP 0 LAST ROOM PVCCIN_CPU1_DECAP_VR
J 0
(-3950 4650);
DISPLAY 1.021277 (-3950 4650);
PAINT ORANGE (-3950 4650);
DISPLAY INVISIBLE (-3950 4650);
FORCEADD CAP_A..1
(-3750 4450);
FORCEPROP 1 LAST LOCATION C2D39
J 0
(-3700 4550);
DISPLAY 0.617021 (-3700 4550);
PAINT AQUA (-3700 4550);
FORCEPROP 1 LAST PART_NUMBER E15431-004
J 0
(-3700 4300);
DISPLAY 0.617021 (-3700 4300);
PAINT BLUE (-3700 4300);
FORCEPROP 1 LAST VALUE 22.0UF
J 0
(-3700 4500);
DISPLAY 0.617021 (-3700 4500);
PAINT SKYBLUE (-3700 4500);
FORCEPROP 1 LAST TOLERANCE 20%
J 0
(-3700 4400);
DISPLAY 0.617021 (-3700 4400);
PAINT SKYBLUE (-3700 4400);
FORCEPROP 1 LAST PACK_TYPE 0603V
J 0
(-3700 4250);
DISPLAY 0.617021 (-3700 4250);
PAINT SKYBLUE (-3700 4250);
FORCEPROP 1 LAST VOLTAGE 4V
J 0
(-3700 4450);
DISPLAY 0.617021 (-3700 4450);
PAINT SKYBLUE (-3700 4450);
FORCEPROP 1 LAST MATERIAL X6S
J 0
(-3700 4350);
DISPLAY 0.617021 (-3700 4350);
PAINT SKYBLUE (-3700 4350);
FORCEPROP 1 LASTPIN (-3750 4550) $PN 1
J 0
(-3740 4530);
DISPLAY 0.617021 (-3740 4530);
PAINT ORANGE (-3740 4530);
FORCEPROP 1 LASTPIN (-3750 4350) $PN 2
J 0
(-3740 4330);
DISPLAY 0.617021 (-3740 4330);
PAINT ORANGE (-3740 4330);
FORCEPROP 2 LAST CDS_LOCATION C2D39
J 0
(-3700 4550);
DISPLAY 0.617021 (-3700 4550);
PAINT AQUA (-3700 4550);
DISPLAY INVISIBLE (-3700 4550);
FORCEPROP 2 LAST BOM_COST PROC
J 0
(-3750 4450);
PAINT MONO (-3750 4450);
DISPLAY INVISIBLE (-3750 4450);
FORCEPROP 2 LAST CDS_LIB dev_discrete
J 0
(-3750 4450);
PAINT ORANGE (-3750 4450);
DISPLAY INVISIBLE (-3750 4450);
FORCEPROP 2 LAST CDS_SEC 1
J 0
(-3700 4650);
PAINT MONO (-3700 4650);
DISPLAY INVISIBLE (-3700 4650);
FORCEPROP 2 LAST $SEC 1
J 0
(-3700 4650);
PAINT MONO (-3700 4650);
DISPLAY INVISIBLE (-3700 4650);
FORCEPROP 1 LAST PATH I165
J 0
(-3700 4600);
DISPLAY 0.978723 (-3700 4600);
PAINT WHITE (-3700 4600);
DISPLAY INVISIBLE (-3700 4600);
FORCEPROP 2 LAST ROOM PVCCIN_CPU1_DECAP_VR
J 0
(-3700 4550);
PAINT ORANGE (-3700 4550);
DISPLAY INVISIBLE (-3700 4550);
FORCEADD CAP_A..1
(-3500 4450);
FORCEPROP 1 LAST LOCATION C3D17
J 0
(-3450 4550);
DISPLAY 0.617021 (-3450 4550);
PAINT AQUA (-3450 4550);
FORCEPROP 1 LAST PART_NUMBER E15431-004
J 0
(-3450 4300);
DISPLAY 0.617021 (-3450 4300);
PAINT BLUE (-3450 4300);
FORCEPROP 1 LAST VALUE 22.0UF
J 0
(-3450 4500);
DISPLAY 0.617021 (-3450 4500);
PAINT SKYBLUE (-3450 4500);
FORCEPROP 1 LAST TOLERANCE 20%
J 0
(-3450 4400);
DISPLAY 0.617021 (-3450 4400);
PAINT SKYBLUE (-3450 4400);
FORCEPROP 1 LAST PACK_TYPE 0603V
J 0
(-3450 4250);
DISPLAY 0.617021 (-3450 4250);
PAINT SKYBLUE (-3450 4250);
FORCEPROP 1 LAST VOLTAGE 4V
J 0
(-3450 4450);
DISPLAY 0.617021 (-3450 4450);
PAINT SKYBLUE (-3450 4450);
FORCEPROP 1 LAST MATERIAL X6S
J 0
(-3450 4350);
DISPLAY 0.617021 (-3450 4350);
PAINT SKYBLUE (-3450 4350);
FORCEPROP 1 LASTPIN (-3500 4550) $PN 1
J 0
(-3490 4530);
DISPLAY 0.617021 (-3490 4530);
PAINT ORANGE (-3490 4530);
FORCEPROP 1 LASTPIN (-3500 4350) $PN 2
J 0
(-3490 4330);
DISPLAY 0.617021 (-3490 4330);
PAINT ORANGE (-3490 4330);
FORCEPROP 2 LAST CDS_LOCATION C3D17
J 0
(-3450 4550);
DISPLAY 0.617021 (-3450 4550);
PAINT AQUA (-3450 4550);
DISPLAY INVISIBLE (-3450 4550);
FORCEPROP 2 LAST BOM_COST PROC
J 0
(-3500 4450);
PAINT MONO (-3500 4450);
DISPLAY INVISIBLE (-3500 4450);
FORCEPROP 2 LAST CDS_LIB dev_discrete
J 0
(-3500 4450);
PAINT ORANGE (-3500 4450);
DISPLAY INVISIBLE (-3500 4450);
FORCEPROP 2 LAST CDS_SEC 1
J 0
(-3450 4650);
PAINT MONO (-3450 4650);
DISPLAY INVISIBLE (-3450 4650);
FORCEPROP 2 LAST $SEC 1
J 0
(-3450 4650);
PAINT MONO (-3450 4650);
DISPLAY INVISIBLE (-3450 4650);
FORCEPROP 1 LAST PATH I166
J 0
(-3450 4600);
DISPLAY 0.978723 (-3450 4600);
PAINT WHITE (-3450 4600);
DISPLAY INVISIBLE (-3450 4600);
FORCEPROP 2 LAST ROOM PVCCIN_CPU1_DECAP_VR
J 0
(-3450 4550);
PAINT ORANGE (-3450 4550);
DISPLAY INVISIBLE (-3450 4550);
FORCEADD PVCCIO_CPU1..1
(-3975 4025);
FORCEPROP 3 LASTPIN (-3975 3975) SIG_NAME PVCCIO_CPU1\g
J 0
(-3965 3985);
DISPLAY 0.659574 (-3965 3985);
PAINT MONO (-3965 3985);
DISPLAY INVISIBLE (-3965 3985);
FORCEPROP 1 LAST VOLTAGE 1.1V
J 0
(-4020 3982);
DISPLAY 0.340426 (-4020 3982);
PAINT SKYBLUE (-4020 3982);
DISPLAY INVISIBLE (-4020 3982);
FORCEPROP 2 LAST CDS_LIB mstr_symbols
J 0
(-3975 4025);
PAINT ORANGE (-3975 4025);
DISPLAY INVISIBLE (-3975 4025);
FORCEPROP 1 LAST BODY_TYPE PLUMBING
J 0
(-4020 3982);
DISPLAY 0.340426 (-4020 3982);
PAINT GREEN (-4020 3982);
DISPLAY INVISIBLE (-4020 3982);
FORCEPROP 1 LAST PATH I167
J 0
(-3925 4050);
DISPLAY 0.872340 (-3925 4050);
PAINT AQUA (-3925 4050);
DISPLAY INVISIBLE (-3925 4050);
FORCEPROP 1 LAST HDL_POWER PVCCIO_CPU1
J 1
(-3975 4075);
DISPLAY 0.872340 (-3975 4075);
PAINT GREEN (-3975 4075);
DISPLAY INVISIBLE (-3975 4075);
FORCEADD CAP_A..1
(-975 4450);
FORCEPROP 1 LAST LOCATION C3D18
J 0
(-925 4550);
DISPLAY 0.617021 (-925 4550);
PAINT AQUA (-925 4550);
FORCEPROP 1 LAST PART_NUMBER E15431-004
J 0
(-925 4300);
DISPLAY 0.617021 (-925 4300);
PAINT BLUE (-925 4300);
FORCEPROP 1 LAST VALUE 22.0UF
J 0
(-925 4500);
DISPLAY 0.617021 (-925 4500);
PAINT SKYBLUE (-925 4500);
FORCEPROP 1 LAST TOLERANCE 20%
J 0
(-925 4400);
DISPLAY 0.617021 (-925 4400);
PAINT SKYBLUE (-925 4400);
FORCEPROP 1 LAST PACK_TYPE 0603V
J 0
(-925 4250);
DISPLAY 0.617021 (-925 4250);
PAINT SKYBLUE (-925 4250);
FORCEPROP 1 LAST VOLTAGE 4V
J 0
(-925 4450);
DISPLAY 0.617021 (-925 4450);
PAINT SKYBLUE (-925 4450);
FORCEPROP 1 LAST MATERIAL X6S
J 0
(-925 4350);
DISPLAY 0.617021 (-925 4350);
PAINT SKYBLUE (-925 4350);
FORCEPROP 1 LASTPIN (-975 4550) $PN 1
J 0
(-965 4530);
DISPLAY 0.617021 (-965 4530);
PAINT ORANGE (-965 4530);
FORCEPROP 1 LASTPIN (-975 4350) $PN 2
J 0
(-965 4330);
DISPLAY 0.617021 (-965 4330);
PAINT ORANGE (-965 4330);
FORCEPROP 2 LAST CDS_LOCATION C3D18
J 0
(-925 4550);
DISPLAY 0.617021 (-925 4550);
PAINT AQUA (-925 4550);
DISPLAY INVISIBLE (-925 4550);
FORCEPROP 2 LAST BOM_COST PROC
J 0
(-975 4450);
PAINT MONO (-975 4450);
DISPLAY INVISIBLE (-975 4450);
FORCEPROP 2 LAST CDS_LIB dev_discrete
J 0
(-975 4450);
PAINT ORANGE (-975 4450);
DISPLAY INVISIBLE (-975 4450);
FORCEPROP 2 LAST CDS_SEC 1
J 0
(-925 4650);
PAINT MONO (-925 4650);
DISPLAY INVISIBLE (-925 4650);
FORCEPROP 2 LAST $SEC 1
J 0
(-925 4650);
PAINT MONO (-925 4650);
DISPLAY INVISIBLE (-925 4650);
FORCEPROP 1 LAST PATH I169
J 0
(-925 4600);
DISPLAY 0.978723 (-925 4600);
PAINT WHITE (-925 4600);
DISPLAY INVISIBLE (-925 4600);
FORCEPROP 2 LAST ROOM PVCCIN_CPU1_DECAP_VR
J 0
(-925 4550);
PAINT ORANGE (-925 4550);
DISPLAY INVISIBLE (-925 4550);
FORCEADD CAP_A..1
(-725 4450);
FORCEPROP 1 LAST LOCATION C3D6
J 0
(-675 4550);
DISPLAY 0.617021 (-675 4550);
PAINT AQUA (-675 4550);
FORCEPROP 1 LAST PART_NUMBER E15431-004
J 0
(-675 4300);
DISPLAY 0.617021 (-675 4300);
PAINT BLUE (-675 4300);
FORCEPROP 1 LAST VALUE 22.0UF
J 0
(-675 4500);
DISPLAY 0.617021 (-675 4500);
PAINT SKYBLUE (-675 4500);
FORCEPROP 1 LAST TOLERANCE 20%
J 0
(-675 4400);
DISPLAY 0.617021 (-675 4400);
PAINT SKYBLUE (-675 4400);
FORCEPROP 1 LAST PACK_TYPE 0603V
J 0
(-675 4250);
DISPLAY 0.617021 (-675 4250);
PAINT SKYBLUE (-675 4250);
FORCEPROP 1 LAST VOLTAGE 4V
J 0
(-675 4450);
DISPLAY 0.617021 (-675 4450);
PAINT SKYBLUE (-675 4450);
FORCEPROP 1 LAST MATERIAL X6S
J 0
(-675 4350);
DISPLAY 0.617021 (-675 4350);
PAINT SKYBLUE (-675 4350);
FORCEPROP 1 LASTPIN (-725 4550) $PN 1
J 0
(-715 4530);
DISPLAY 0.617021 (-715 4530);
PAINT ORANGE (-715 4530);
FORCEPROP 1 LASTPIN (-725 4350) $PN 2
J 0
(-715 4330);
DISPLAY 0.617021 (-715 4330);
PAINT ORANGE (-715 4330);
FORCEPROP 2 LAST CDS_LOCATION C3D6
J 0
(-675 4550);
DISPLAY 0.617021 (-675 4550);
PAINT AQUA (-675 4550);
DISPLAY INVISIBLE (-675 4550);
FORCEPROP 2 LAST BOM_COST PROC
J 0
(-725 4450);
PAINT MONO (-725 4450);
DISPLAY INVISIBLE (-725 4450);
FORCEPROP 2 LAST CDS_LIB dev_discrete
J 0
(-725 4450);
PAINT ORANGE (-725 4450);
DISPLAY INVISIBLE (-725 4450);
FORCEPROP 2 LAST CDS_SEC 1
J 0
(-675 4650);
PAINT MONO (-675 4650);
DISPLAY INVISIBLE (-675 4650);
FORCEPROP 2 LAST $SEC 1
J 0
(-675 4650);
PAINT MONO (-675 4650);
DISPLAY INVISIBLE (-675 4650);
FORCEPROP 1 LAST PATH I170
J 0
(-675 4600);
DISPLAY 0.978723 (-675 4600);
PAINT WHITE (-675 4600);
DISPLAY INVISIBLE (-675 4600);
FORCEPROP 2 LAST ROOM PVCCIN_CPU1_DECAP_VR
J 0
(-675 4550);
PAINT ORANGE (-675 4550);
DISPLAY INVISIBLE (-675 4550);
FORCEADD CAP_A..1
(-2725 4450);
FORCEPROP 1 LAST LOCATION C3D14
J 0
(-2675 4550);
DISPLAY 0.617021 (-2675 4550);
PAINT AQUA (-2675 4550);
FORCEPROP 1 LAST PART_NUMBER E15431-004
J 0
(-2675 4300);
DISPLAY 0.617021 (-2675 4300);
PAINT BLUE (-2675 4300);
FORCEPROP 1 LAST VALUE 22.0UF
J 0
(-2675 4500);
DISPLAY 0.617021 (-2675 4500);
PAINT SKYBLUE (-2675 4500);
FORCEPROP 1 LAST TOLERANCE 20%
J 0
(-2675 4400);
DISPLAY 0.617021 (-2675 4400);
PAINT SKYBLUE (-2675 4400);
FORCEPROP 1 LAST PACK_TYPE 0603V
J 0
(-2675 4250);
DISPLAY 0.617021 (-2675 4250);
PAINT SKYBLUE (-2675 4250);
FORCEPROP 1 LAST VOLTAGE 4V
J 0
(-2675 4450);
DISPLAY 0.617021 (-2675 4450);
PAINT SKYBLUE (-2675 4450);
FORCEPROP 1 LAST MATERIAL X6S
J 0
(-2675 4350);
DISPLAY 0.617021 (-2675 4350);
PAINT SKYBLUE (-2675 4350);
FORCEPROP 1 LASTPIN (-2725 4550) $PN 1
J 0
(-2715 4530);
DISPLAY 0.617021 (-2715 4530);
PAINT ORANGE (-2715 4530);
FORCEPROP 1 LASTPIN (-2725 4350) $PN 2
J 0
(-2715 4330);
DISPLAY 0.617021 (-2715 4330);
PAINT ORANGE (-2715 4330);
FORCEPROP 2 LAST CDS_LOCATION C3D14
J 0
(-2675 4550);
DISPLAY 0.617021 (-2675 4550);
PAINT AQUA (-2675 4550);
DISPLAY INVISIBLE (-2675 4550);
FORCEPROP 2 LAST BOM_COST PROC
J 0
(-2725 4450);
PAINT MONO (-2725 4450);
DISPLAY INVISIBLE (-2725 4450);
FORCEPROP 2 LAST CDS_LIB dev_discrete
J 0
(-2725 4450);
PAINT ORANGE (-2725 4450);
DISPLAY INVISIBLE (-2725 4450);
FORCEPROP 2 LAST CDS_SEC 1
J 0
(-2675 4650);
PAINT MONO (-2675 4650);
DISPLAY INVISIBLE (-2675 4650);
FORCEPROP 2 LAST $SEC 1
J 0
(-2675 4650);
PAINT MONO (-2675 4650);
DISPLAY INVISIBLE (-2675 4650);
FORCEPROP 1 LAST PATH I171
J 0
(-2675 4600);
DISPLAY 0.978723 (-2675 4600);
PAINT WHITE (-2675 4600);
DISPLAY INVISIBLE (-2675 4600);
FORCEPROP 2 LAST ROOM PVCCIN_CPU1_DECAP_VR
J 0
(-2675 4550);
PAINT ORANGE (-2675 4550);
DISPLAY INVISIBLE (-2675 4550);
FORCEADD CAP_A..1
(-3975 3750);
FORCEPROP 1 LAST LOCATION C3D23
J 0
(-3925 3850);
DISPLAY 0.617021 (-3925 3850);
PAINT AQUA (-3925 3850);
FORCEPROP 1 LAST PART_NUMBER E15431-004
J 0
(-3925 3600);
DISPLAY 0.617021 (-3925 3600);
PAINT BLUE (-3925 3600);
FORCEPROP 1 LAST VALUE 22.0UF
J 0
(-3925 3800);
DISPLAY 0.617021 (-3925 3800);
PAINT SKYBLUE (-3925 3800);
FORCEPROP 1 LAST TOLERANCE 20%
J 0
(-3925 3700);
DISPLAY 0.617021 (-3925 3700);
PAINT SKYBLUE (-3925 3700);
FORCEPROP 1 LAST PACK_TYPE 0603V
J 0
(-3925 3550);
DISPLAY 0.617021 (-3925 3550);
PAINT SKYBLUE (-3925 3550);
FORCEPROP 1 LAST VOLTAGE 4V
J 0
(-3925 3750);
DISPLAY 0.617021 (-3925 3750);
PAINT SKYBLUE (-3925 3750);
FORCEPROP 1 LAST MATERIAL X6S
J 0
(-3925 3650);
DISPLAY 0.617021 (-3925 3650);
PAINT SKYBLUE (-3925 3650);
FORCEPROP 1 LASTPIN (-3975 3850) $PN 1
J 0
(-3965 3830);
DISPLAY 0.617021 (-3965 3830);
PAINT ORANGE (-3965 3830);
FORCEPROP 1 LASTPIN (-3975 3650) $PN 2
J 0
(-3965 3630);
DISPLAY 0.617021 (-3965 3630);
PAINT ORANGE (-3965 3630);
FORCEPROP 2 LAST CDS_LOCATION C3D23
J 0
(-3925 3850);
DISPLAY 0.617021 (-3925 3850);
PAINT AQUA (-3925 3850);
DISPLAY INVISIBLE (-3925 3850);
FORCEPROP 2 LAST BOM_COST PROC
J 0
(-3975 3750);
PAINT MONO (-3975 3750);
DISPLAY INVISIBLE (-3975 3750);
FORCEPROP 2 LAST CDS_LIB dev_discrete
J 0
(-3975 3750);
PAINT ORANGE (-3975 3750);
DISPLAY INVISIBLE (-3975 3750);
FORCEPROP 2 LAST CDS_SEC 1
J 0
(-3925 3950);
PAINT MONO (-3925 3950);
DISPLAY INVISIBLE (-3925 3950);
FORCEPROP 2 LAST $SEC 1
J 0
(-3925 3950);
PAINT MONO (-3925 3950);
DISPLAY INVISIBLE (-3925 3950);
FORCEPROP 1 LAST PATH I172
J 0
(-3925 3900);
DISPLAY 0.978723 (-3925 3900);
PAINT WHITE (-3925 3900);
DISPLAY INVISIBLE (-3925 3900);
FORCEPROP 2 LAST ROOM PVCCIN_CPU1_DECAP_VR
J 0
(-3925 3850);
PAINT ORANGE (-3925 3850);
DISPLAY INVISIBLE (-3925 3850);
FORCEADD CAP_A..1
(-3675 3750);
FORCEPROP 1 LAST LOCATION C3D15
J 0
(-3625 3850);
DISPLAY 0.617021 (-3625 3850);
PAINT AQUA (-3625 3850);
FORCEPROP 1 LAST PART_NUMBER E15431-004
J 0
(-3625 3600);
DISPLAY 0.617021 (-3625 3600);
PAINT BLUE (-3625 3600);
FORCEPROP 1 LAST VALUE 22.0UF
J 0
(-3625 3800);
DISPLAY 0.617021 (-3625 3800);
PAINT SKYBLUE (-3625 3800);
FORCEPROP 1 LAST TOLERANCE 20%
J 0
(-3625 3700);
DISPLAY 0.617021 (-3625 3700);
PAINT SKYBLUE (-3625 3700);
FORCEPROP 1 LAST PACK_TYPE 0603V
J 0
(-3625 3550);
DISPLAY 0.617021 (-3625 3550);
PAINT SKYBLUE (-3625 3550);
FORCEPROP 1 LAST VOLTAGE 4V
J 0
(-3625 3750);
DISPLAY 0.617021 (-3625 3750);
PAINT SKYBLUE (-3625 3750);
FORCEPROP 1 LAST MATERIAL X6S
J 0
(-3625 3650);
DISPLAY 0.617021 (-3625 3650);
PAINT SKYBLUE (-3625 3650);
FORCEPROP 1 LASTPIN (-3675 3850) $PN 1
J 0
(-3665 3830);
DISPLAY 0.617021 (-3665 3830);
PAINT ORANGE (-3665 3830);
FORCEPROP 1 LASTPIN (-3675 3650) $PN 2
J 0
(-3665 3630);
DISPLAY 0.617021 (-3665 3630);
PAINT ORANGE (-3665 3630);
FORCEPROP 2 LAST CDS_LOCATION C3D15
J 0
(-3625 3850);
DISPLAY 0.617021 (-3625 3850);
PAINT AQUA (-3625 3850);
DISPLAY INVISIBLE (-3625 3850);
FORCEPROP 2 LAST BOM_COST PROC
J 0
(-3675 3750);
PAINT MONO (-3675 3750);
DISPLAY INVISIBLE (-3675 3750);
FORCEPROP 2 LAST CDS_LIB dev_discrete
J 0
(-3675 3750);
PAINT ORANGE (-3675 3750);
DISPLAY INVISIBLE (-3675 3750);
FORCEPROP 2 LAST CDS_SEC 1
J 0
(-3625 3950);
PAINT MONO (-3625 3950);
DISPLAY INVISIBLE (-3625 3950);
FORCEPROP 2 LAST $SEC 1
J 0
(-3625 3950);
PAINT MONO (-3625 3950);
DISPLAY INVISIBLE (-3625 3950);
FORCEPROP 1 LAST PATH I174
J 0
(-3625 3900);
DISPLAY 0.978723 (-3625 3900);
PAINT WHITE (-3625 3900);
DISPLAY INVISIBLE (-3625 3900);
FORCEPROP 2 LAST ROOM PVCCIN_CPU1_DECAP_VR
J 0
(-3625 3850);
PAINT ORANGE (-3625 3850);
DISPLAY INVISIBLE (-3625 3850);
FORCEADD CAP_A..1
(-3350 3775);
FORCEPROP 1 LAST LOCATION C3D24
J 0
(-3300 3875);
DISPLAY 0.617021 (-3300 3875);
PAINT AQUA (-3300 3875);
FORCEPROP 1 LAST PART_NUMBER E15431-004
J 0
(-3300 3625);
DISPLAY 0.617021 (-3300 3625);
PAINT BLUE (-3300 3625);
FORCEPROP 1 LAST VALUE 22.0UF
J 0
(-3300 3825);
DISPLAY 0.617021 (-3300 3825);
PAINT SKYBLUE (-3300 3825);
FORCEPROP 1 LAST TOLERANCE 20%
J 0
(-3300 3725);
DISPLAY 0.617021 (-3300 3725);
PAINT SKYBLUE (-3300 3725);
FORCEPROP 1 LAST PACK_TYPE 0603V
J 0
(-3300 3575);
DISPLAY 0.617021 (-3300 3575);
PAINT SKYBLUE (-3300 3575);
FORCEPROP 1 LAST VOLTAGE 4V
J 0
(-3300 3775);
DISPLAY 0.617021 (-3300 3775);
PAINT SKYBLUE (-3300 3775);
FORCEPROP 1 LAST MATERIAL X6S
J 0
(-3300 3675);
DISPLAY 0.617021 (-3300 3675);
PAINT SKYBLUE (-3300 3675);
FORCEPROP 1 LASTPIN (-3350 3875) $PN 1
J 0
(-3340 3855);
DISPLAY 0.617021 (-3340 3855);
PAINT ORANGE (-3340 3855);
FORCEPROP 1 LASTPIN (-3350 3675) $PN 2
J 0
(-3340 3655);
DISPLAY 0.617021 (-3340 3655);
PAINT ORANGE (-3340 3655);
FORCEPROP 2 LAST CDS_LOCATION C3D24
J 0
(-3300 3875);
DISPLAY 0.617021 (-3300 3875);
PAINT AQUA (-3300 3875);
DISPLAY INVISIBLE (-3300 3875);
FORCEPROP 2 LAST BOM_COST PROC
J 0
(-3350 3775);
PAINT MONO (-3350 3775);
DISPLAY INVISIBLE (-3350 3775);
FORCEPROP 2 LAST CDS_LIB dev_discrete
J 0
(-3350 3775);
PAINT ORANGE (-3350 3775);
DISPLAY INVISIBLE (-3350 3775);
FORCEPROP 2 LAST CDS_SEC 1
J 0
(-3300 3975);
PAINT MONO (-3300 3975);
DISPLAY INVISIBLE (-3300 3975);
FORCEPROP 2 LAST $SEC 1
J 0
(-3300 3975);
PAINT MONO (-3300 3975);
DISPLAY INVISIBLE (-3300 3975);
FORCEPROP 1 LAST PATH I175
J 0
(-3300 3925);
DISPLAY 0.978723 (-3300 3925);
PAINT WHITE (-3300 3925);
DISPLAY INVISIBLE (-3300 3925);
FORCEPROP 2 LAST ROOM PVCCIN_CPU1_DECAP_VR
J 0
(-3300 3875);
PAINT ORANGE (-3300 3875);
DISPLAY INVISIBLE (-3300 3875);
FORCEADD CAP_A..1
(-3050 3775);
FORCEPROP 1 LAST LOCATION C3D16
J 0
(-3000 3875);
DISPLAY 0.617021 (-3000 3875);
PAINT AQUA (-3000 3875);
FORCEPROP 1 LAST PART_NUMBER E15431-004
J 0
(-3000 3625);
DISPLAY 0.617021 (-3000 3625);
PAINT BLUE (-3000 3625);
FORCEPROP 1 LAST VALUE 22.0UF
J 0
(-3000 3825);
DISPLAY 0.617021 (-3000 3825);
PAINT SKYBLUE (-3000 3825);
FORCEPROP 1 LAST TOLERANCE 20%
J 0
(-3000 3725);
DISPLAY 0.617021 (-3000 3725);
PAINT SKYBLUE (-3000 3725);
FORCEPROP 1 LAST PACK_TYPE 0603V
J 0
(-3000 3575);
DISPLAY 0.617021 (-3000 3575);
PAINT SKYBLUE (-3000 3575);
FORCEPROP 1 LAST VOLTAGE 4V
J 0
(-3000 3775);
DISPLAY 0.617021 (-3000 3775);
PAINT SKYBLUE (-3000 3775);
FORCEPROP 1 LAST MATERIAL X6S
J 0
(-3000 3675);
DISPLAY 0.617021 (-3000 3675);
PAINT SKYBLUE (-3000 3675);
FORCEPROP 1 LASTPIN (-3050 3875) $PN 1
J 0
(-3040 3855);
DISPLAY 0.617021 (-3040 3855);
PAINT ORANGE (-3040 3855);
FORCEPROP 1 LASTPIN (-3050 3675) $PN 2
J 0
(-3040 3655);
DISPLAY 0.617021 (-3040 3655);
PAINT ORANGE (-3040 3655);
FORCEPROP 2 LAST CDS_LOCATION C3D16
J 0
(-3000 3875);
DISPLAY 0.617021 (-3000 3875);
PAINT AQUA (-3000 3875);
DISPLAY INVISIBLE (-3000 3875);
FORCEPROP 2 LAST BOM_COST PROC
J 0
(-3050 3775);
PAINT MONO (-3050 3775);
DISPLAY INVISIBLE (-3050 3775);
FORCEPROP 2 LAST CDS_LIB dev_discrete
J 0
(-3050 3775);
PAINT ORANGE (-3050 3775);
DISPLAY INVISIBLE (-3050 3775);
FORCEPROP 2 LAST CDS_SEC 1
J 0
(-3000 3975);
PAINT MONO (-3000 3975);
DISPLAY INVISIBLE (-3000 3975);
FORCEPROP 2 LAST $SEC 1
J 0
(-3000 3975);
PAINT MONO (-3000 3975);
DISPLAY INVISIBLE (-3000 3975);
FORCEPROP 1 LAST PATH I176
J 0
(-3000 3925);
DISPLAY 0.978723 (-3000 3925);
PAINT WHITE (-3000 3925);
DISPLAY INVISIBLE (-3000 3925);
FORCEPROP 2 LAST ROOM PVCCIN_CPU1_DECAP_VR
J 0
(-3000 3875);
PAINT ORANGE (-3000 3875);
DISPLAY INVISIBLE (-3000 3875);
FORCEADD CAP_A..1
(-2375 925);
FORCEPROP 1 LAST LOCATION C7P12
J 0
(-2325 1025);
DISPLAY 0.617021 (-2325 1025);
PAINT AQUA (-2325 1025);
FORCEPROP 1 LAST PART_NUMBER E15431-004
J 0
(-2325 775);
DISPLAY 0.617021 (-2325 775);
PAINT BLUE (-2325 775);
FORCEPROP 1 LAST VALUE 22.0UF
J 0
(-2325 975);
DISPLAY 0.617021 (-2325 975);
PAINT SKYBLUE (-2325 975);
FORCEPROP 1 LAST TOLERANCE 20%
J 0
(-2325 875);
DISPLAY 0.617021 (-2325 875);
PAINT SKYBLUE (-2325 875);
FORCEPROP 1 LAST PACK_TYPE 0603V
J 0
(-2325 725);
DISPLAY 0.617021 (-2325 725);
PAINT SKYBLUE (-2325 725);
FORCEPROP 1 LAST VOLTAGE 4V
J 0
(-2325 925);
DISPLAY 0.617021 (-2325 925);
PAINT SKYBLUE (-2325 925);
FORCEPROP 1 LAST MATERIAL X6S
J 0
(-2325 825);
DISPLAY 0.617021 (-2325 825);
PAINT SKYBLUE (-2325 825);
FORCEPROP 1 LASTPIN (-2375 1025) $PN 1
J 0
(-2365 1005);
DISPLAY 0.617021 (-2365 1005);
PAINT ORANGE (-2365 1005);
FORCEPROP 1 LASTPIN (-2375 825) $PN 2
J 0
(-2365 805);
DISPLAY 0.617021 (-2365 805);
PAINT ORANGE (-2365 805);
FORCEPROP 2 LAST CDS_LOCATION C7P12
J 0
(-2325 1025);
DISPLAY 0.617021 (-2325 1025);
PAINT AQUA (-2325 1025);
DISPLAY INVISIBLE (-2325 1025);
FORCEPROP 2 LAST BOM_COST PROC
J 0
(-2375 925);
PAINT MONO (-2375 925);
DISPLAY INVISIBLE (-2375 925);
FORCEPROP 2 LAST CDS_LIB dev_discrete
J 0
(-2375 925);
PAINT ORANGE (-2375 925);
DISPLAY INVISIBLE (-2375 925);
FORCEPROP 2 LAST CDS_SEC 1
J 0
(-2325 1125);
PAINT MONO (-2325 1125);
DISPLAY INVISIBLE (-2325 1125);
FORCEPROP 2 LAST $SEC 1
J 0
(-2325 1125);
PAINT MONO (-2325 1125);
DISPLAY INVISIBLE (-2325 1125);
FORCEPROP 1 LAST PATH I179
J 0
(-2325 1075);
DISPLAY 0.978723 (-2325 1075);
PAINT WHITE (-2325 1075);
DISPLAY INVISIBLE (-2325 1075);
FORCEPROP 2 LAST ROOM PVCCIN_CPU1_DECAP_VR
J 0
(-2325 1025);
PAINT ORANGE (-2325 1025);
DISPLAY INVISIBLE (-2325 1025);
FORCEADD CAP_A..1
(-2750 3775);
FORCEPROP 1 LAST LOCATION C3D8
J 0
(-2700 3875);
DISPLAY 0.617021 (-2700 3875);
PAINT AQUA (-2700 3875);
FORCEPROP 1 LAST PART_NUMBER E15431-004
J 0
(-2700 3625);
DISPLAY 0.617021 (-2700 3625);
PAINT BLUE (-2700 3625);
FORCEPROP 1 LAST VALUE 22.0UF
J 0
(-2700 3825);
DISPLAY 0.617021 (-2700 3825);
PAINT SKYBLUE (-2700 3825);
FORCEPROP 1 LAST TOLERANCE 20%
J 0
(-2700 3725);
DISPLAY 0.617021 (-2700 3725);
PAINT SKYBLUE (-2700 3725);
FORCEPROP 1 LAST PACK_TYPE 0603V
J 0
(-2700 3575);
DISPLAY 0.617021 (-2700 3575);
PAINT SKYBLUE (-2700 3575);
FORCEPROP 1 LAST VOLTAGE 4V
J 0
(-2700 3775);
DISPLAY 0.617021 (-2700 3775);
PAINT SKYBLUE (-2700 3775);
FORCEPROP 1 LAST MATERIAL X6S
J 0
(-2700 3675);
DISPLAY 0.617021 (-2700 3675);
PAINT SKYBLUE (-2700 3675);
FORCEPROP 1 LASTPIN (-2750 3875) $PN 1
J 0
(-2740 3855);
DISPLAY 0.617021 (-2740 3855);
PAINT GREEN (-2740 3855);
FORCEPROP 1 LASTPIN (-2750 3675) $PN 2
J 0
(-2740 3655);
DISPLAY 0.617021 (-2740 3655);
PAINT GREEN (-2740 3655);
FORCEPROP 2 LAST CDS_LOCATION C3D8
J 0
(-2700 3875);
DISPLAY 0.617021 (-2700 3875);
PAINT AQUA (-2700 3875);
DISPLAY INVISIBLE (-2700 3875);
FORCEPROP 2 LAST BOM_COST PROC
J 0
(-2750 3775);
PAINT MONO (-2750 3775);
DISPLAY INVISIBLE (-2750 3775);
FORCEPROP 2 LAST CDS_LIB dev_discrete
J 0
(-2750 3775);
PAINT ORANGE (-2750 3775);
DISPLAY INVISIBLE (-2750 3775);
FORCEPROP 2 LAST CDS_SEC 1
J 0
(-2700 3975);
PAINT MONO (-2700 3975);
DISPLAY INVISIBLE (-2700 3975);
FORCEPROP 2 LAST $SEC 1
J 0
(-2700 3975);
PAINT MONO (-2700 3975);
DISPLAY INVISIBLE (-2700 3975);
FORCEPROP 1 LAST PATH I18
J 0
(-2700 3925);
DISPLAY 0.978723 (-2700 3925);
PAINT WHITE (-2700 3925);
DISPLAY INVISIBLE (-2700 3925);
FORCEPROP 2 LAST ROOM PVCCIN_CPU1_DECAP_VR
J 0
(-2700 3875);
PAINT ORANGE (-2700 3875);
DISPLAY INVISIBLE (-2700 3875);
FORCEADD CAP..1
(-4775 2150);
FORCEPROP 1 LAST LOCATION C7P9
J 0
(-4725 2250);
DISPLAY 0.617021 (-4725 2250);
PAINT AQUA (-4725 2250);
FORCEPROP 1 LAST PART_NUMBER C95333-006
R 1
J 0
(-4825 1975);
DISPLAY 0.617021 (-4825 1975);
PAINT BLUE (-4825 1975);
FORCEPROP 1 LAST VALUE 47UF
J 0
(-4725 2200);
DISPLAY 0.617021 (-4725 2200);
PAINT SKYBLUE (-4725 2200);
FORCEPROP 1 LAST TOLERANCE 20%
J 0
(-4725 2100);
DISPLAY 0.617021 (-4725 2100);
PAINT SKYBLUE (-4725 2100);
FORCEPROP 1 LAST PACK_TYPE 0805
J 0
(-4725 1950);
DISPLAY 0.617021 (-4725 1950);
PAINT SKYBLUE (-4725 1950);
FORCEPROP 1 LAST VOLTAGE 4V
J 0
(-4725 2150);
DISPLAY 0.617021 (-4725 2150);
PAINT SKYBLUE (-4725 2150);
FORCEPROP 1 LAST MATERIAL X6S
J 0
(-4725 2050);
DISPLAY 0.617021 (-4725 2050);
PAINT SKYBLUE (-4725 2050);
FORCEPROP 1 LASTPIN (-4775 2050) $PN 2
J 0
(-4765 2030);
DISPLAY 0.617021 (-4765 2030);
PAINT ORANGE (-4765 2030);
FORCEPROP 1 LASTPIN (-4775 2250) $PN 1
J 0
(-4765 2230);
DISPLAY 0.617021 (-4765 2230);
PAINT ORANGE (-4765 2230);
FORCEPROP 2 LAST BOM_COST PROC
J 0
(-4775 2150);
PAINT MONO (-4775 2150);
DISPLAY INVISIBLE (-4775 2150);
FORCEPROP 2 LAST CDS_LIB mstr_discrete
J 0
(-4775 2150);
PAINT ORANGE (-4775 2150);
DISPLAY INVISIBLE (-4775 2150);
FORCEPROP 2 LAST SEC_TYPE 0805
J 0
(-4725 2350);
DISPLAY 1.021277 (-4725 2350);
PAINT ORANGE (-4725 2350);
DISPLAY INVISIBLE (-4725 2350);
FORCEPROP 2 LAST SEC 1
J 0
(-4725 2350);
DISPLAY 0.680851 (-4725 2350);
PAINT MONO (-4725 2350);
DISPLAY INVISIBLE (-4725 2350);
FORCEPROP 2 LAST CDS_LOCATION C7P9
J 0
(-4725 2250);
DISPLAY 0.617021 (-4725 2250);
PAINT AQUA (-4725 2250);
DISPLAY INVISIBLE (-4725 2250);
FORCEPROP 1 LAST PATH I181
J 0
(-4725 2300);
DISPLAY 0.978723 (-4725 2300);
PAINT WHITE (-4725 2300);
DISPLAY INVISIBLE (-4725 2300);
FORCEPROP 2 LAST ROOM PVCCIN_CPU1_DECAP_VR
J 0
(-4725 2250);
PAINT ORANGE (-4725 2250);
DISPLAY INVISIBLE (-4725 2250);
FORCEADD CAP..1
(-4525 2150);
FORCEPROP 1 LAST LOCATION C7P5
J 0
(-4475 2250);
DISPLAY 0.617021 (-4475 2250);
PAINT AQUA (-4475 2250);
FORCEPROP 1 LAST PART_NUMBER C95333-006
R 1
J 0
(-4575 1975);
DISPLAY 0.617021 (-4575 1975);
PAINT BLUE (-4575 1975);
FORCEPROP 1 LAST VALUE 47UF
J 0
(-4475 2200);
DISPLAY 0.617021 (-4475 2200);
PAINT SKYBLUE (-4475 2200);
FORCEPROP 1 LAST TOLERANCE 20%
J 0
(-4475 2100);
DISPLAY 0.617021 (-4475 2100);
PAINT SKYBLUE (-4475 2100);
FORCEPROP 1 LAST PACK_TYPE 0805
J 0
(-4475 2000);
DISPLAY 0.617021 (-4475 2000);
PAINT SKYBLUE (-4475 2000);
FORCEPROP 1 LAST MATERIAL X6S
J 0
(-4475 2050);
DISPLAY 0.617021 (-4475 2050);
PAINT SKYBLUE (-4475 2050);
FORCEPROP 1 LASTPIN (-4525 2050) $PN 2
J 0
(-4515 2030);
DISPLAY 0.617021 (-4515 2030);
PAINT ORANGE (-4515 2030);
FORCEPROP 1 LASTPIN (-4525 2250) $PN 1
J 0
(-4515 2230);
DISPLAY 0.617021 (-4515 2230);
PAINT ORANGE (-4515 2230);
FORCEPROP 1 LAST VOLTAGE 4V
J 0
(-4475 2150);
PAINT SKYBLUE (-4475 2150);
DISPLAY INVISIBLE (-4475 2150);
FORCEPROP 2 LAST CDS_LIB mstr_discrete
J 0
(-4525 2150);
PAINT ORANGE (-4525 2150);
DISPLAY INVISIBLE (-4525 2150);
FORCEPROP 2 LAST BOM_COST PROC
J 0
(-4525 2150);
PAINT MONO (-4525 2150);
DISPLAY INVISIBLE (-4525 2150);
FORCEPROP 2 LAST CDS_SEC 1
J 0
(-4475 2350);
PAINT MONO (-4475 2350);
DISPLAY INVISIBLE (-4475 2350);
FORCEPROP 2 LAST $SEC 1
J 0
(-4475 2350);
PAINT MONO (-4475 2350);
DISPLAY INVISIBLE (-4475 2350);
FORCEPROP 2 LAST CDS_LOCATION C7P5
J 0
(-4475 2250);
DISPLAY 0.617021 (-4475 2250);
PAINT AQUA (-4475 2250);
DISPLAY INVISIBLE (-4475 2250);
FORCEPROP 1 LAST PATH I182
J 0
(-4475 2300);
DISPLAY 0.978723 (-4475 2300);
PAINT WHITE (-4475 2300);
DISPLAY INVISIBLE (-4475 2300);
FORCEPROP 2 LAST ROOM PVCCIN_CPU1_DECAP_VR
J 0
(-4475 2250);
PAINT ORANGE (-4475 2250);
DISPLAY INVISIBLE (-4475 2250);
FORCEADD CAP..1
(-3425 2150);
FORCEPROP 1 LAST LOCATION C7P11
J 0
(-3375 2250);
DISPLAY 0.617021 (-3375 2250);
PAINT AQUA (-3375 2250);
FORCEPROP 1 LAST PART_NUMBER C95333-006
R 1
J 0
(-3475 1975);
DISPLAY 0.617021 (-3475 1975);
PAINT BLUE (-3475 1975);
FORCEPROP 1 LAST VALUE 47UF
J 0
(-3375 2200);
DISPLAY 0.617021 (-3375 2200);
PAINT SKYBLUE (-3375 2200);
FORCEPROP 1 LAST TOLERANCE 20%
J 0
(-3375 2100);
DISPLAY 0.617021 (-3375 2100);
PAINT SKYBLUE (-3375 2100);
FORCEPROP 1 LAST PACK_TYPE 0805
J 0
(-3375 2000);
DISPLAY 0.617021 (-3375 2000);
PAINT SKYBLUE (-3375 2000);
FORCEPROP 1 LAST MATERIAL X6S
J 0
(-3375 2050);
DISPLAY 0.617021 (-3375 2050);
PAINT SKYBLUE (-3375 2050);
FORCEPROP 1 LASTPIN (-3425 2050) $PN 2
J 0
(-3415 2030);
DISPLAY 0.617021 (-3415 2030);
PAINT ORANGE (-3415 2030);
FORCEPROP 1 LASTPIN (-3425 2250) $PN 1
J 0
(-3415 2230);
DISPLAY 0.617021 (-3415 2230);
PAINT ORANGE (-3415 2230);
FORCEPROP 1 LAST VOLTAGE 4V
J 0
(-3375 2150);
PAINT SKYBLUE (-3375 2150);
DISPLAY INVISIBLE (-3375 2150);
FORCEPROP 2 LAST CDS_LIB mstr_discrete
J 0
(-3425 2150);
PAINT ORANGE (-3425 2150);
DISPLAY INVISIBLE (-3425 2150);
FORCEPROP 2 LAST BOM_COST PROC
J 0
(-3425 2150);
PAINT MONO (-3425 2150);
DISPLAY INVISIBLE (-3425 2150);
FORCEPROP 2 LAST CDS_SEC 1
J 0
(-3375 2350);
PAINT MONO (-3375 2350);
DISPLAY INVISIBLE (-3375 2350);
FORCEPROP 2 LAST $SEC 1
J 0
(-3375 2350);
PAINT MONO (-3375 2350);
DISPLAY INVISIBLE (-3375 2350);
FORCEPROP 2 LAST CDS_LOCATION C7P11
J 0
(-3375 2250);
DISPLAY 0.617021 (-3375 2250);
PAINT AQUA (-3375 2250);
DISPLAY INVISIBLE (-3375 2250);
FORCEPROP 1 LAST PATH I183
J 0
(-3375 2300);
DISPLAY 0.978723 (-3375 2300);
PAINT WHITE (-3375 2300);
DISPLAY INVISIBLE (-3375 2300);
FORCEPROP 2 LAST ROOM PVCCIN_CPU1_DECAP_VR
J 0
(-3375 2250);
PAINT ORANGE (-3375 2250);
DISPLAY INVISIBLE (-3375 2250);
FORCEADD CAP..1
(-3175 2150);
FORCEPROP 1 LAST LOCATION C7P8
J 0
(-3125 2250);
DISPLAY 0.617021 (-3125 2250);
PAINT AQUA (-3125 2250);
FORCEPROP 1 LAST PART_NUMBER C95333-006
R 1
J 0
(-3225 1975);
DISPLAY 0.617021 (-3225 1975);
PAINT BLUE (-3225 1975);
FORCEPROP 1 LAST VALUE 47UF
J 0
(-3125 2200);
DISPLAY 0.617021 (-3125 2200);
PAINT SKYBLUE (-3125 2200);
FORCEPROP 1 LAST TOLERANCE 20%
J 0
(-3125 2100);
DISPLAY 0.617021 (-3125 2100);
PAINT SKYBLUE (-3125 2100);
FORCEPROP 1 LAST PACK_TYPE 0805
J 0
(-3125 2000);
DISPLAY 0.617021 (-3125 2000);
PAINT SKYBLUE (-3125 2000);
FORCEPROP 1 LAST MATERIAL X6S
J 0
(-3125 2050);
DISPLAY 0.617021 (-3125 2050);
PAINT SKYBLUE (-3125 2050);
FORCEPROP 1 LASTPIN (-3175 2050) $PN 2
J 0
(-3165 2030);
DISPLAY 0.617021 (-3165 2030);
PAINT ORANGE (-3165 2030);
FORCEPROP 1 LASTPIN (-3175 2250) $PN 1
J 0
(-3165 2230);
DISPLAY 0.617021 (-3165 2230);
PAINT ORANGE (-3165 2230);
FORCEPROP 1 LAST VOLTAGE 4V
J 0
(-3125 2150);
PAINT SKYBLUE (-3125 2150);
DISPLAY INVISIBLE (-3125 2150);
FORCEPROP 2 LAST CDS_LIB mstr_discrete
J 0
(-3175 2150);
PAINT ORANGE (-3175 2150);
DISPLAY INVISIBLE (-3175 2150);
FORCEPROP 2 LAST BOM_COST PROC
J 0
(-3175 2150);
PAINT MONO (-3175 2150);
DISPLAY INVISIBLE (-3175 2150);
FORCEPROP 2 LAST CDS_SEC 1
J 0
(-3125 2350);
PAINT MONO (-3125 2350);
DISPLAY INVISIBLE (-3125 2350);
FORCEPROP 2 LAST $SEC 1
J 0
(-3125 2350);
PAINT MONO (-3125 2350);
DISPLAY INVISIBLE (-3125 2350);
FORCEPROP 2 LAST CDS_LOCATION C7P8
J 0
(-3125 2250);
DISPLAY 0.617021 (-3125 2250);
PAINT AQUA (-3125 2250);
DISPLAY INVISIBLE (-3125 2250);
FORCEPROP 1 LAST PATH I184
J 0
(-3125 2300);
DISPLAY 0.978723 (-3125 2300);
PAINT WHITE (-3125 2300);
DISPLAY INVISIBLE (-3125 2300);
FORCEPROP 2 LAST ROOM PVCCIN_CPU1_DECAP_VR
J 0
(-3125 2250);
PAINT ORANGE (-3125 2250);
DISPLAY INVISIBLE (-3125 2250);
FORCEADD CAP..1
(-1450 2125);
FORCEPROP 1 LAST LOCATION C7P4
J 0
(-1400 2225);
DISPLAY 0.617021 (-1400 2225);
PAINT AQUA (-1400 2225);
FORCEPROP 1 LAST PART_NUMBER C95333-006
R 1
J 0
(-1500 1950);
DISPLAY 0.617021 (-1500 1950);
PAINT BLUE (-1500 1950);
FORCEPROP 1 LAST VALUE 47UF
J 0
(-1400 2175);
DISPLAY 0.617021 (-1400 2175);
PAINT SKYBLUE (-1400 2175);
FORCEPROP 1 LAST TOLERANCE 20%
J 0
(-1400 2075);
DISPLAY 0.617021 (-1400 2075);
PAINT SKYBLUE (-1400 2075);
FORCEPROP 1 LAST PACK_TYPE 0805
J 0
(-1400 1975);
DISPLAY 0.617021 (-1400 1975);
PAINT SKYBLUE (-1400 1975);
FORCEPROP 1 LASTPIN (-1450 2025) $PN 2
J 0
(-1440 2005);
DISPLAY 0.617021 (-1440 2005);
PAINT ORANGE (-1440 2005);
FORCEPROP 1 LASTPIN (-1450 2225) $PN 1
J 0
(-1440 2205);
DISPLAY 0.617021 (-1440 2205);
PAINT ORANGE (-1440 2205);
FORCEPROP 1 LAST VOLTAGE 4V
J 0
(-1400 2125);
PAINT SKYBLUE (-1400 2125);
DISPLAY INVISIBLE (-1400 2125);
FORCEPROP 1 LAST MATERIAL X6S
J 0
(-1400 2025);
PAINT SKYBLUE (-1400 2025);
DISPLAY INVISIBLE (-1400 2025);
FORCEPROP 2 LAST BOM_COST PROC
J 0
(-1450 2125);
PAINT MONO (-1450 2125);
DISPLAY INVISIBLE (-1450 2125);
FORCEPROP 2 LAST CDS_LIB mstr_discrete
J 0
(-1450 2125);
PAINT ORANGE (-1450 2125);
DISPLAY INVISIBLE (-1450 2125);
FORCEPROP 2 LAST CDS_SEC 1
J 0
(-1400 2325);
PAINT MONO (-1400 2325);
DISPLAY INVISIBLE (-1400 2325);
FORCEPROP 2 LAST $SEC 1
J 0
(-1400 2325);
PAINT MONO (-1400 2325);
DISPLAY INVISIBLE (-1400 2325);
FORCEPROP 2 LAST CDS_LOCATION C7P4
J 0
(-1400 2225);
DISPLAY 0.617021 (-1400 2225);
PAINT AQUA (-1400 2225);
DISPLAY INVISIBLE (-1400 2225);
FORCEPROP 1 LAST PATH I195
J 0
(-1400 2275);
DISPLAY 0.978723 (-1400 2275);
PAINT WHITE (-1400 2275);
DISPLAY INVISIBLE (-1400 2275);
FORCEPROP 2 LAST ROOM PVCCIN_CPU1_DECAP_VR
J 0
(-1400 2225);
PAINT ORANGE (-1400 2225);
DISPLAY INVISIBLE (-1400 2225);
FORCEADD CAP_A..1
(-1950 3725);
FORCEPROP 1 LAST LOCATION C3D10
J 0
(-1900 3825);
DISPLAY 0.617021 (-1900 3825);
PAINT AQUA (-1900 3825);
FORCEPROP 1 LAST PART_NUMBER E15431-004
J 0
(-1900 3575);
DISPLAY 0.617021 (-1900 3575);
PAINT BLUE (-1900 3575);
FORCEPROP 1 LAST VALUE 22.0UF
J 0
(-1900 3775);
DISPLAY 0.617021 (-1900 3775);
PAINT SKYBLUE (-1900 3775);
FORCEPROP 1 LAST TOLERANCE 20%
J 0
(-1900 3675);
DISPLAY 0.617021 (-1900 3675);
PAINT SKYBLUE (-1900 3675);
FORCEPROP 1 LAST PACK_TYPE 0603V
J 0
(-1900 3525);
DISPLAY 0.617021 (-1900 3525);
PAINT SKYBLUE (-1900 3525);
FORCEPROP 1 LAST VOLTAGE 4V
J 0
(-1900 3725);
DISPLAY 0.617021 (-1900 3725);
PAINT SKYBLUE (-1900 3725);
FORCEPROP 1 LAST MATERIAL X6S
J 0
(-1900 3625);
DISPLAY 0.617021 (-1900 3625);
PAINT SKYBLUE (-1900 3625);
FORCEPROP 2 LAST CDS_LOCATION C3D10
J 0
(-1900 3825);
DISPLAY 0.617021 (-1900 3825);
PAINT AQUA (-1900 3825);
DISPLAY INVISIBLE (-1900 3825);
FORCEPROP 2 LAST BOM_COST PROC
J 0
(-1950 3725);
PAINT MONO (-1950 3725);
DISPLAY INVISIBLE (-1950 3725);
FORCEPROP 2 LAST CDS_LIB dev_discrete
J 0
(-1950 3725);
PAINT ORANGE (-1950 3725);
DISPLAY INVISIBLE (-1950 3725);
FORCEPROP 2 LAST CDS_SEC 1
J 0
(-1900 3925);
PAINT MONO (-1900 3925);
DISPLAY INVISIBLE (-1900 3925);
FORCEPROP 2 LAST $SEC 1
J 0
(-1900 3925);
PAINT MONO (-1900 3925);
DISPLAY INVISIBLE (-1900 3925);
FORCEPROP 1 LAST PATH I196
J 0
(-1900 3875);
DISPLAY 0.978723 (-1900 3875);
PAINT WHITE (-1900 3875);
DISPLAY INVISIBLE (-1900 3875);
FORCEPROP 2 LAST ROOM PVCCIN_CPU1_DECAP_VR
J 0
(-1900 3825);
PAINT ORANGE (-1900 3825);
DISPLAY INVISIBLE (-1900 3825);
FORCEPROP 1 LASTPIN (-1950 3825) $PN 1
J 0
(-1940 3805);
DISPLAY 0.787234 (-1940 3805);
PAINT ORANGE (-1940 3805);
DISPLAY INVISIBLE (-1940 3805);
FORCEPROP 1 LASTPIN (-1950 3625) $PN 2
J 0
(-1940 3605);
DISPLAY 0.787234 (-1940 3605);
PAINT ORANGE (-1940 3605);
DISPLAY INVISIBLE (-1940 3605);
FORCEADD CAP_A..1
(-1700 3725);
FORCEPROP 1 LAST LOCATION C2D18
J 0
(-1650 3825);
DISPLAY 0.617021 (-1650 3825);
PAINT AQUA (-1650 3825);
FORCEPROP 1 LAST PART_NUMBER E15431-004
J 0
(-1650 3575);
DISPLAY 0.617021 (-1650 3575);
PAINT BLUE (-1650 3575);
FORCEPROP 1 LAST VALUE 22.0UF
J 0
(-1650 3775);
DISPLAY 0.617021 (-1650 3775);
PAINT SKYBLUE (-1650 3775);
FORCEPROP 1 LAST TOLERANCE 20%
J 0
(-1650 3675);
DISPLAY 0.617021 (-1650 3675);
PAINT SKYBLUE (-1650 3675);
FORCEPROP 1 LAST PACK_TYPE 0603V
J 0
(-1650 3525);
DISPLAY 0.617021 (-1650 3525);
PAINT SKYBLUE (-1650 3525);
FORCEPROP 1 LAST VOLTAGE 4V
J 0
(-1650 3725);
DISPLAY 0.617021 (-1650 3725);
PAINT SKYBLUE (-1650 3725);
FORCEPROP 1 LAST MATERIAL X6S
J 0
(-1650 3625);
DISPLAY 0.617021 (-1650 3625);
PAINT SKYBLUE (-1650 3625);
FORCEPROP 2 LAST CDS_LOCATION C2D18
J 0
(-1650 3825);
DISPLAY 0.617021 (-1650 3825);
PAINT AQUA (-1650 3825);
DISPLAY INVISIBLE (-1650 3825);
FORCEPROP 2 LAST BOM_COST PROC
J 0
(-1700 3725);
PAINT MONO (-1700 3725);
DISPLAY INVISIBLE (-1700 3725);
FORCEPROP 2 LAST CDS_LIB dev_discrete
J 0
(-1700 3725);
PAINT ORANGE (-1700 3725);
DISPLAY INVISIBLE (-1700 3725);
FORCEPROP 2 LAST CDS_SEC 1
J 0
(-1650 3925);
PAINT MONO (-1650 3925);
DISPLAY INVISIBLE (-1650 3925);
FORCEPROP 2 LAST $SEC 1
J 0
(-1650 3925);
PAINT MONO (-1650 3925);
DISPLAY INVISIBLE (-1650 3925);
FORCEPROP 1 LAST PATH I197
J 0
(-1650 3875);
DISPLAY 0.978723 (-1650 3875);
PAINT WHITE (-1650 3875);
DISPLAY INVISIBLE (-1650 3875);
FORCEPROP 2 LAST ROOM PVCCIN_CPU1_DECAP_VR
J 0
(-1650 3825);
PAINT ORANGE (-1650 3825);
DISPLAY INVISIBLE (-1650 3825);
FORCEPROP 1 LASTPIN (-1700 3825) $PN 1
J 0
(-1690 3805);
DISPLAY 0.787234 (-1690 3805);
PAINT ORANGE (-1690 3805);
DISPLAY INVISIBLE (-1690 3805);
FORCEPROP 1 LASTPIN (-1700 3625) $PN 2
J 0
(-1690 3605);
DISPLAY 0.787234 (-1690 3605);
PAINT ORANGE (-1690 3605);
DISPLAY INVISIBLE (-1690 3605);
FORCEADD CAP_A..1
(-1450 3725);
FORCEPROP 1 LAST LOCATION C2D28
J 0
(-1400 3825);
DISPLAY 0.617021 (-1400 3825);
PAINT AQUA (-1400 3825);
FORCEPROP 1 LAST PART_NUMBER E15431-004
J 0
(-1400 3575);
DISPLAY 0.617021 (-1400 3575);
PAINT BLUE (-1400 3575);
FORCEPROP 1 LAST VALUE 22.0UF
J 0
(-1400 3775);
DISPLAY 0.617021 (-1400 3775);
PAINT SKYBLUE (-1400 3775);
FORCEPROP 1 LAST TOLERANCE 20%
J 0
(-1400 3675);
DISPLAY 0.617021 (-1400 3675);
PAINT SKYBLUE (-1400 3675);
FORCEPROP 1 LAST PACK_TYPE 0603V
J 0
(-1400 3525);
DISPLAY 0.617021 (-1400 3525);
PAINT SKYBLUE (-1400 3525);
FORCEPROP 1 LAST VOLTAGE 4V
J 0
(-1400 3725);
DISPLAY 0.617021 (-1400 3725);
PAINT SKYBLUE (-1400 3725);
FORCEPROP 1 LAST MATERIAL X6S
J 0
(-1400 3625);
DISPLAY 0.617021 (-1400 3625);
PAINT SKYBLUE (-1400 3625);
FORCEPROP 2 LAST CDS_LOCATION C2D28
J 0
(-1400 3825);
DISPLAY 0.617021 (-1400 3825);
PAINT AQUA (-1400 3825);
DISPLAY INVISIBLE (-1400 3825);
FORCEPROP 2 LAST BOM_COST PROC
J 0
(-1450 3725);
PAINT MONO (-1450 3725);
DISPLAY INVISIBLE (-1450 3725);
FORCEPROP 2 LAST CDS_LIB dev_discrete
J 0
(-1450 3725);
PAINT ORANGE (-1450 3725);
DISPLAY INVISIBLE (-1450 3725);
FORCEPROP 2 LAST CDS_SEC 1
J 0
(-1400 3925);
PAINT MONO (-1400 3925);
DISPLAY INVISIBLE (-1400 3925);
FORCEPROP 2 LAST $SEC 1
J 0
(-1400 3925);
PAINT MONO (-1400 3925);
DISPLAY INVISIBLE (-1400 3925);
FORCEPROP 1 LAST PATH I198
J 0
(-1400 3875);
DISPLAY 0.978723 (-1400 3875);
PAINT WHITE (-1400 3875);
DISPLAY INVISIBLE (-1400 3875);
FORCEPROP 2 LAST ROOM PVCCIN_CPU1_DECAP_VR
J 0
(-1400 3825);
PAINT ORANGE (-1400 3825);
DISPLAY INVISIBLE (-1400 3825);
FORCEPROP 1 LASTPIN (-1450 3825) $PN 1
J 0
(-1440 3805);
DISPLAY 0.787234 (-1440 3805);
PAINT ORANGE (-1440 3805);
DISPLAY INVISIBLE (-1440 3805);
FORCEPROP 1 LASTPIN (-1450 3625) $PN 2
J 0
(-1440 3605);
DISPLAY 0.787234 (-1440 3605);
PAINT ORANGE (-1440 3605);
DISPLAY INVISIBLE (-1440 3605);
FORCEADD CAP_A..1
(-1200 3725);
FORCEPROP 1 LAST LOCATION C2D29
J 0
(-1150 3825);
DISPLAY 0.617021 (-1150 3825);
PAINT AQUA (-1150 3825);
FORCEPROP 1 LAST PART_NUMBER E15431-004
J 0
(-1150 3575);
DISPLAY 0.617021 (-1150 3575);
PAINT BLUE (-1150 3575);
FORCEPROP 1 LAST VALUE 22.0UF
J 0
(-1150 3775);
DISPLAY 0.617021 (-1150 3775);
PAINT SKYBLUE (-1150 3775);
FORCEPROP 1 LAST TOLERANCE 20%
J 0
(-1150 3675);
DISPLAY 0.617021 (-1150 3675);
PAINT SKYBLUE (-1150 3675);
FORCEPROP 1 LAST PACK_TYPE 0603V
J 0
(-1150 3525);
DISPLAY 0.617021 (-1150 3525);
PAINT SKYBLUE (-1150 3525);
FORCEPROP 1 LAST VOLTAGE 4V
J 0
(-1150 3725);
DISPLAY 0.617021 (-1150 3725);
PAINT SKYBLUE (-1150 3725);
FORCEPROP 1 LAST MATERIAL X6S
J 0
(-1150 3625);
DISPLAY 0.617021 (-1150 3625);
PAINT SKYBLUE (-1150 3625);
FORCEPROP 2 LAST CDS_LOCATION C2D29
J 0
(-1150 3825);
DISPLAY 0.617021 (-1150 3825);
PAINT AQUA (-1150 3825);
DISPLAY INVISIBLE (-1150 3825);
FORCEPROP 2 LAST BOM_COST PROC
J 0
(-1200 3725);
PAINT MONO (-1200 3725);
DISPLAY INVISIBLE (-1200 3725);
FORCEPROP 2 LAST CDS_LIB dev_discrete
J 0
(-1200 3725);
PAINT ORANGE (-1200 3725);
DISPLAY INVISIBLE (-1200 3725);
FORCEPROP 2 LAST CDS_SEC 1
J 0
(-1150 3925);
PAINT MONO (-1150 3925);
DISPLAY INVISIBLE (-1150 3925);
FORCEPROP 2 LAST $SEC 1
J 0
(-1150 3925);
PAINT MONO (-1150 3925);
DISPLAY INVISIBLE (-1150 3925);
FORCEPROP 1 LAST PATH I199
J 0
(-1150 3875);
DISPLAY 0.978723 (-1150 3875);
PAINT WHITE (-1150 3875);
DISPLAY INVISIBLE (-1150 3875);
FORCEPROP 2 LAST ROOM PVCCIN_CPU1_DECAP_VR
J 0
(-1150 3825);
PAINT ORANGE (-1150 3825);
DISPLAY INVISIBLE (-1150 3825);
FORCEPROP 1 LASTPIN (-1200 3825) $PN 1
J 0
(-1190 3805);
DISPLAY 0.787234 (-1190 3805);
PAINT ORANGE (-1190 3805);
DISPLAY INVISIBLE (-1190 3805);
FORCEPROP 1 LASTPIN (-1200 3625) $PN 2
J 0
(-1190 3605);
DISPLAY 0.787234 (-1190 3605);
PAINT ORANGE (-1190 3605);
DISPLAY INVISIBLE (-1190 3605);
FORCEADD GND..1
(-725 4100);
FORCEPROP 3 LASTPIN (-725 4150) SIG_NAME GND\g
J 0
(-715 4160);
DISPLAY 0.659574 (-715 4160);
PAINT MONO (-715 4160);
DISPLAY INVISIBLE (-715 4160);
FORCEPROP 1 LAST VOLTAGE 0
J 0
(-725 4100);
PAINT SKYBLUE (-725 4100);
DISPLAY INVISIBLE (-725 4100);
FORCEPROP 1 LAST SIZE 1B
J 0
(-650 4050);
DISPLAY 0.893617 (-650 4050);
PAINT GREEN (-650 4050);
DISPLAY INVISIBLE (-650 4050);
FORCEPROP 2 LAST CDS_LIB mstr_symbols
J 0
(-725 4100);
PAINT ORANGE (-725 4100);
DISPLAY INVISIBLE (-725 4100);
FORCEPROP 1 LAST BODY_TYPE PLUMBING
J 0
(-770 4057);
DISPLAY 0.340426 (-770 4057);
PAINT GREEN (-770 4057);
DISPLAY INVISIBLE (-770 4057);
FORCEPROP 1 LAST PATH I2
J 0
(-650 4100);
DISPLAY 0.872340 (-650 4100);
PAINT AQUA (-650 4100);
DISPLAY INVISIBLE (-650 4100);
FORCEPROP 2 LAST ROOM PVCCIN_CPU1_DECAP_VR
J 0
(-1275 4175);
PAINT ORANGE (-1275 4175);
DISPLAY INVISIBLE (-1275 4175);
FORCEPROP 1 LAST HDL_POWER GND
J 0
(-725 4250);
DISPLAY 0.893617 (-725 4250);
PAINT GREEN (-725 4250);
DISPLAY INVISIBLE (-725 4250);
FORCEADD CAP_A..1
(-7725 4450);
FORCEPROP 1 LAST LOCATION C2D2
J 0
(-7675 4550);
DISPLAY 0.617021 (-7675 4550);
PAINT AQUA (-7675 4550);
FORCEPROP 1 LAST PART_NUMBER E15431-004
J 0
(-7675 4300);
DISPLAY 0.617021 (-7675 4300);
PAINT BLUE (-7675 4300);
FORCEPROP 1 LAST VALUE 22.0UF
J 0
(-7675 4500);
DISPLAY 0.617021 (-7675 4500);
PAINT SKYBLUE (-7675 4500);
FORCEPROP 1 LAST TOLERANCE 20%
J 0
(-7675 4400);
DISPLAY 0.617021 (-7675 4400);
PAINT SKYBLUE (-7675 4400);
FORCEPROP 1 LAST PACK_TYPE 0603V
J 0
(-7675 4250);
DISPLAY 0.617021 (-7675 4250);
PAINT SKYBLUE (-7675 4250);
FORCEPROP 1 LAST VOLTAGE 4V
J 0
(-7675 4450);
DISPLAY 0.617021 (-7675 4450);
PAINT SKYBLUE (-7675 4450);
FORCEPROP 1 LAST MATERIAL X6S
J 0
(-7675 4350);
DISPLAY 0.617021 (-7675 4350);
PAINT SKYBLUE (-7675 4350);
FORCEPROP 2 LAST CDS_LOCATION C2D2
J 0
(-7675 4550);
DISPLAY 0.617021 (-7675 4550);
PAINT AQUA (-7675 4550);
DISPLAY INVISIBLE (-7675 4550);
FORCEPROP 2 LAST BOM_COST PROC
J 0
(-7725 4450);
PAINT MONO (-7725 4450);
DISPLAY INVISIBLE (-7725 4450);
FORCEPROP 2 LAST CDS_LIB dev_discrete
J 0
(-7725 4450);
PAINT ORANGE (-7725 4450);
DISPLAY INVISIBLE (-7725 4450);
FORCEPROP 2 LAST CDS_SEC 1
J 0
(-7675 4650);
PAINT MONO (-7675 4650);
DISPLAY INVISIBLE (-7675 4650);
FORCEPROP 2 LAST $SEC 1
J 0
(-7675 4650);
PAINT MONO (-7675 4650);
DISPLAY INVISIBLE (-7675 4650);
FORCEPROP 1 LAST PATH I201
J 0
(-7675 4600);
DISPLAY 0.978723 (-7675 4600);
PAINT WHITE (-7675 4600);
DISPLAY INVISIBLE (-7675 4600);
FORCEPROP 2 LAST ROOM PVCCIN_CPU1_DECAP_VR
J 0
(-7675 4550);
PAINT ORANGE (-7675 4550);
DISPLAY INVISIBLE (-7675 4550);
FORCEPROP 1 LASTPIN (-7725 4550) $PN 1
J 0
(-7715 4530);
DISPLAY 0.787234 (-7715 4530);
PAINT ORANGE (-7715 4530);
DISPLAY INVISIBLE (-7715 4530);
FORCEPROP 1 LASTPIN (-7725 4350) $PN 2
J 0
(-7715 4330);
DISPLAY 0.787234 (-7715 4330);
PAINT ORANGE (-7715 4330);
DISPLAY INVISIBLE (-7715 4330);
FORCEADD CAP_A..1
(-6675 4450);
FORCEPROP 1 LAST LOCATION C2D3
J 0
(-6625 4550);
DISPLAY 0.617021 (-6625 4550);
PAINT AQUA (-6625 4550);
FORCEPROP 1 LAST PART_NUMBER E15431-004
J 0
(-6625 4300);
DISPLAY 0.617021 (-6625 4300);
PAINT BLUE (-6625 4300);
FORCEPROP 1 LAST VALUE 22.0UF
J 0
(-6625 4500);
DISPLAY 0.617021 (-6625 4500);
PAINT SKYBLUE (-6625 4500);
FORCEPROP 1 LAST TOLERANCE 20%
J 0
(-6625 4400);
DISPLAY 0.617021 (-6625 4400);
PAINT SKYBLUE (-6625 4400);
FORCEPROP 1 LAST PACK_TYPE 0603V
J 0
(-6625 4250);
DISPLAY 0.617021 (-6625 4250);
PAINT SKYBLUE (-6625 4250);
FORCEPROP 1 LAST VOLTAGE 4V
J 0
(-6625 4450);
DISPLAY 0.617021 (-6625 4450);
PAINT SKYBLUE (-6625 4450);
FORCEPROP 1 LAST MATERIAL X6S
J 0
(-6625 4350);
DISPLAY 0.617021 (-6625 4350);
PAINT SKYBLUE (-6625 4350);
FORCEPROP 2 LAST CDS_LOCATION C2D3
J 0
(-6625 4550);
DISPLAY 0.617021 (-6625 4550);
PAINT AQUA (-6625 4550);
DISPLAY INVISIBLE (-6625 4550);
FORCEPROP 2 LAST BOM_COST PROC
J 0
(-6675 4450);
PAINT MONO (-6675 4450);
DISPLAY INVISIBLE (-6675 4450);
FORCEPROP 2 LAST CDS_LIB dev_discrete
J 0
(-6675 4450);
PAINT ORANGE (-6675 4450);
DISPLAY INVISIBLE (-6675 4450);
FORCEPROP 2 LAST CDS_SEC 1
J 0
(-6625 4650);
PAINT MONO (-6625 4650);
DISPLAY INVISIBLE (-6625 4650);
FORCEPROP 2 LAST $SEC 1
J 0
(-6625 4650);
PAINT MONO (-6625 4650);
DISPLAY INVISIBLE (-6625 4650);
FORCEPROP 1 LAST PATH I202
J 0
(-6625 4600);
DISPLAY 0.978723 (-6625 4600);
PAINT WHITE (-6625 4600);
DISPLAY INVISIBLE (-6625 4600);
FORCEPROP 2 LAST ROOM PVCCIN_CPU1_DECAP_VR
J 0
(-6625 4550);
PAINT ORANGE (-6625 4550);
DISPLAY INVISIBLE (-6625 4550);
FORCEPROP 1 LASTPIN (-6675 4550) $PN 1
J 0
(-6665 4530);
DISPLAY 0.787234 (-6665 4530);
PAINT ORANGE (-6665 4530);
DISPLAY INVISIBLE (-6665 4530);
FORCEPROP 1 LASTPIN (-6675 4350) $PN 2
J 0
(-6665 4330);
DISPLAY 0.787234 (-6665 4330);
PAINT ORANGE (-6665 4330);
DISPLAY INVISIBLE (-6665 4330);
FORCEADD CAP_A..1
(-6650 3775);
FORCEPROP 1 LAST LOCATION C2D47
J 0
(-6600 3875);
DISPLAY 0.617021 (-6600 3875);
PAINT AQUA (-6600 3875);
FORCEPROP 1 LAST PART_NUMBER E15431-004
J 0
(-6600 3625);
DISPLAY 0.617021 (-6600 3625);
PAINT BLUE (-6600 3625);
FORCEPROP 1 LAST VALUE 22.0UF
J 0
(-6600 3825);
DISPLAY 0.617021 (-6600 3825);
PAINT SKYBLUE (-6600 3825);
FORCEPROP 1 LAST TOLERANCE 20%
J 0
(-6600 3725);
DISPLAY 0.617021 (-6600 3725);
PAINT SKYBLUE (-6600 3725);
FORCEPROP 1 LAST PACK_TYPE 0603V
J 0
(-6600 3575);
DISPLAY 0.617021 (-6600 3575);
PAINT SKYBLUE (-6600 3575);
FORCEPROP 1 LAST VOLTAGE 4V
J 0
(-6600 3775);
DISPLAY 0.617021 (-6600 3775);
PAINT SKYBLUE (-6600 3775);
FORCEPROP 1 LAST MATERIAL X6S
J 0
(-6600 3675);
DISPLAY 0.617021 (-6600 3675);
PAINT SKYBLUE (-6600 3675);
FORCEPROP 2 LAST CDS_LOCATION C2D47
J 0
(-6600 3875);
DISPLAY 0.617021 (-6600 3875);
PAINT AQUA (-6600 3875);
DISPLAY INVISIBLE (-6600 3875);
FORCEPROP 2 LAST BOM_COST PROC
J 0
(-6650 3775);
PAINT MONO (-6650 3775);
DISPLAY INVISIBLE (-6650 3775);
FORCEPROP 2 LAST CDS_LIB dev_discrete
J 0
(-6650 3775);
PAINT ORANGE (-6650 3775);
DISPLAY INVISIBLE (-6650 3775);
FORCEPROP 2 LAST CDS_SEC 1
J 0
(-6600 3975);
PAINT MONO (-6600 3975);
DISPLAY INVISIBLE (-6600 3975);
FORCEPROP 2 LAST $SEC 1
J 0
(-6600 3975);
PAINT MONO (-6600 3975);
DISPLAY INVISIBLE (-6600 3975);
FORCEPROP 1 LAST PATH I203
J 0
(-6600 3925);
DISPLAY 0.978723 (-6600 3925);
PAINT WHITE (-6600 3925);
DISPLAY INVISIBLE (-6600 3925);
FORCEPROP 2 LAST ROOM PVCCIN_CPU1_DECAP_VR
J 0
(-6600 3875);
PAINT ORANGE (-6600 3875);
DISPLAY INVISIBLE (-6600 3875);
FORCEPROP 1 LASTPIN (-6650 3875) $PN 1
J 0
(-6640 3855);
DISPLAY 0.787234 (-6640 3855);
PAINT ORANGE (-6640 3855);
DISPLAY INVISIBLE (-6640 3855);
FORCEPROP 1 LASTPIN (-6650 3675) $PN 2
J 0
(-6640 3655);
DISPLAY 0.787234 (-6640 3655);
PAINT ORANGE (-6640 3655);
DISPLAY INVISIBLE (-6640 3655);
FORCEADD CAP_A..1
(-5275 4450);
FORCEPROP 1 LAST LOCATION C2D46
J 0
(-5225 4550);
DISPLAY 0.617021 (-5225 4550);
PAINT AQUA (-5225 4550);
FORCEPROP 1 LAST PART_NUMBER E15431-004
J 0
(-5225 4300);
DISPLAY 0.617021 (-5225 4300);
PAINT BLUE (-5225 4300);
FORCEPROP 1 LAST VALUE 22.0UF
J 0
(-5225 4500);
DISPLAY 0.617021 (-5225 4500);
PAINT SKYBLUE (-5225 4500);
FORCEPROP 1 LAST TOLERANCE 20%
J 0
(-5225 4400);
DISPLAY 0.617021 (-5225 4400);
PAINT SKYBLUE (-5225 4400);
FORCEPROP 1 LAST PACK_TYPE 0603V
J 0
(-5225 4250);
DISPLAY 0.617021 (-5225 4250);
PAINT SKYBLUE (-5225 4250);
FORCEPROP 1 LAST VOLTAGE 4V
J 0
(-5225 4450);
DISPLAY 0.617021 (-5225 4450);
PAINT SKYBLUE (-5225 4450);
FORCEPROP 1 LAST MATERIAL X6S
J 0
(-5225 4350);
DISPLAY 0.617021 (-5225 4350);
PAINT SKYBLUE (-5225 4350);
FORCEPROP 2 LAST CDS_LOCATION C2D46
J 0
(-5225 4550);
DISPLAY 0.617021 (-5225 4550);
PAINT AQUA (-5225 4550);
DISPLAY INVISIBLE (-5225 4550);
FORCEPROP 2 LAST BOM_COST PROC
J 0
(-5275 4450);
PAINT MONO (-5275 4450);
DISPLAY INVISIBLE (-5275 4450);
FORCEPROP 2 LAST CDS_LIB dev_discrete
J 0
(-5275 4450);
PAINT ORANGE (-5275 4450);
DISPLAY INVISIBLE (-5275 4450);
FORCEPROP 2 LAST CDS_SEC 1
J 0
(-5225 4650);
PAINT MONO (-5225 4650);
DISPLAY INVISIBLE (-5225 4650);
FORCEPROP 2 LAST $SEC 1
J 0
(-5225 4650);
PAINT MONO (-5225 4650);
DISPLAY INVISIBLE (-5225 4650);
FORCEPROP 1 LAST PATH I204
J 0
(-5225 4600);
DISPLAY 0.978723 (-5225 4600);
PAINT WHITE (-5225 4600);
DISPLAY INVISIBLE (-5225 4600);
FORCEPROP 2 LAST ROOM PVCCIN_CPU1_DECAP_VR
J 0
(-5225 4550);
PAINT ORANGE (-5225 4550);
DISPLAY INVISIBLE (-5225 4550);
FORCEPROP 1 LASTPIN (-5275 4550) $PN 1
J 0
(-5265 4530);
DISPLAY 0.787234 (-5265 4530);
PAINT ORANGE (-5265 4530);
DISPLAY INVISIBLE (-5265 4530);
FORCEPROP 1 LASTPIN (-5275 4350) $PN 2
J 0
(-5265 4330);
DISPLAY 0.787234 (-5265 4330);
PAINT ORANGE (-5265 4330);
DISPLAY INVISIBLE (-5265 4330);
FORCEADD CAP_A..1
(-5500 3150);
FORCEPROP 1 LAST LOCATION C3D25
J 0
(-5450 3250);
DISPLAY 0.617021 (-5450 3250);
PAINT AQUA (-5450 3250);
FORCEPROP 1 LAST PART_NUMBER E15431-004
J 0
(-5450 3000);
DISPLAY 0.617021 (-5450 3000);
PAINT BLUE (-5450 3000);
FORCEPROP 1 LAST VALUE 22.0UF
J 0
(-5450 3200);
DISPLAY 0.617021 (-5450 3200);
PAINT SKYBLUE (-5450 3200);
FORCEPROP 1 LAST TOLERANCE 20%
J 0
(-5450 3100);
DISPLAY 0.617021 (-5450 3100);
PAINT SKYBLUE (-5450 3100);
FORCEPROP 1 LAST PACK_TYPE 0603V
J 0
(-5450 2950);
DISPLAY 0.617021 (-5450 2950);
PAINT SKYBLUE (-5450 2950);
FORCEPROP 1 LAST VOLTAGE 4V
J 0
(-5450 3150);
DISPLAY 0.617021 (-5450 3150);
PAINT SKYBLUE (-5450 3150);
FORCEPROP 1 LAST MATERIAL X6S
J 0
(-5450 3050);
DISPLAY 0.617021 (-5450 3050);
PAINT SKYBLUE (-5450 3050);
FORCEPROP 2 LAST CDS_LOCATION C3D25
J 0
(-5450 3250);
DISPLAY 0.617021 (-5450 3250);
PAINT AQUA (-5450 3250);
DISPLAY INVISIBLE (-5450 3250);
FORCEPROP 2 LAST BOM_COST PROC
J 0
(-5500 3150);
PAINT MONO (-5500 3150);
DISPLAY INVISIBLE (-5500 3150);
FORCEPROP 2 LAST CDS_LIB dev_discrete
J 0
(-5500 3150);
PAINT ORANGE (-5500 3150);
DISPLAY INVISIBLE (-5500 3150);
FORCEPROP 2 LAST CDS_SEC 1
J 0
(-5450 3350);
PAINT MONO (-5450 3350);
DISPLAY INVISIBLE (-5450 3350);
FORCEPROP 2 LAST $SEC 1
J 0
(-5450 3350);
PAINT MONO (-5450 3350);
DISPLAY INVISIBLE (-5450 3350);
FORCEPROP 1 LAST PATH I205
J 0
(-5450 3300);
DISPLAY 0.978723 (-5450 3300);
PAINT WHITE (-5450 3300);
DISPLAY INVISIBLE (-5450 3300);
FORCEPROP 2 LAST ROOM PVCCIN_CPU1_DECAP_VR
J 0
(-5425 3250);
PAINT ORANGE (-5425 3250);
DISPLAY INVISIBLE (-5425 3250);
FORCEPROP 1 LASTPIN (-5500 3250) $PN 1
J 0
(-5490 3230);
DISPLAY 0.787234 (-5490 3230);
PAINT ORANGE (-5490 3230);
DISPLAY INVISIBLE (-5490 3230);
FORCEPROP 1 LASTPIN (-5500 3050) $PN 2
J 0
(-5490 3030);
DISPLAY 0.787234 (-5490 3030);
PAINT ORANGE (-5490 3030);
DISPLAY INVISIBLE (-5490 3030);
FORCEADD CAP_A..1
(-2100 925);
FORCEPROP 1 LAST LOCATION C7P16
J 0
(-2050 1025);
DISPLAY 0.617021 (-2050 1025);
PAINT AQUA (-2050 1025);
FORCEPROP 1 LAST PART_NUMBER E15431-004
J 0
(-2050 775);
DISPLAY 0.617021 (-2050 775);
PAINT BLUE (-2050 775);
FORCEPROP 1 LAST VALUE 22.0UF
J 0
(-2050 975);
DISPLAY 0.617021 (-2050 975);
PAINT SKYBLUE (-2050 975);
FORCEPROP 1 LAST TOLERANCE 20%
J 0
(-2050 875);
DISPLAY 0.617021 (-2050 875);
PAINT SKYBLUE (-2050 875);
FORCEPROP 1 LAST PACK_TYPE 0603V
J 0
(-2050 725);
DISPLAY 0.617021 (-2050 725);
PAINT SKYBLUE (-2050 725);
FORCEPROP 1 LAST VOLTAGE 4V
J 0
(-2050 925);
DISPLAY 0.617021 (-2050 925);
PAINT SKYBLUE (-2050 925);
FORCEPROP 1 LAST MATERIAL X6S
J 0
(-2050 825);
DISPLAY 0.617021 (-2050 825);
PAINT SKYBLUE (-2050 825);
FORCEPROP 2 LAST CDS_LOCATION C7P16
J 0
(-2050 1025);
DISPLAY 0.617021 (-2050 1025);
PAINT AQUA (-2050 1025);
DISPLAY INVISIBLE (-2050 1025);
FORCEPROP 2 LAST BOM_COST PROC
J 0
(-2100 925);
PAINT MONO (-2100 925);
DISPLAY INVISIBLE (-2100 925);
FORCEPROP 2 LAST CDS_LIB dev_discrete
J 0
(-2100 925);
PAINT ORANGE (-2100 925);
DISPLAY INVISIBLE (-2100 925);
FORCEPROP 2 LAST CDS_SEC 1
J 0
(-2050 1125);
PAINT MONO (-2050 1125);
DISPLAY INVISIBLE (-2050 1125);
FORCEPROP 2 LAST $SEC 1
J 0
(-2050 1125);
PAINT MONO (-2050 1125);
DISPLAY INVISIBLE (-2050 1125);
FORCEPROP 1 LAST PATH I206
J 0
(-2050 1075);
DISPLAY 0.978723 (-2050 1075);
PAINT WHITE (-2050 1075);
DISPLAY INVISIBLE (-2050 1075);
FORCEPROP 2 LAST ROOM PVCCIN_CPU1_DECAP_VR
J 0
(-2050 1025);
PAINT ORANGE (-2050 1025);
DISPLAY INVISIBLE (-2050 1025);
FORCEPROP 1 LASTPIN (-2100 1025) $PN 1
J 0
(-2090 1005);
DISPLAY 0.787234 (-2090 1005);
PAINT ORANGE (-2090 1005);
DISPLAY INVISIBLE (-2090 1005);
FORCEPROP 1 LASTPIN (-2100 825) $PN 2
J 0
(-2090 805);
DISPLAY 0.787234 (-2090 805);
PAINT ORANGE (-2090 805);
DISPLAY INVISIBLE (-2090 805);
FORCEADD CAP_A..1
(-725 3700);
FORCEPROP 1 LAST LOCATION C3D20
J 0
(-675 3800);
DISPLAY 0.617021 (-675 3800);
PAINT AQUA (-675 3800);
FORCEPROP 1 LAST PART_NUMBER E15431-004
J 0
(-675 3550);
DISPLAY 0.617021 (-675 3550);
PAINT BLUE (-675 3550);
FORCEPROP 1 LAST VALUE 22.0UF
J 0
(-675 3750);
DISPLAY 0.617021 (-675 3750);
PAINT SKYBLUE (-675 3750);
FORCEPROP 1 LAST TOLERANCE 20%
J 0
(-675 3650);
DISPLAY 0.617021 (-675 3650);
PAINT SKYBLUE (-675 3650);
FORCEPROP 1 LAST PACK_TYPE 0603V
J 0
(-675 3500);
DISPLAY 0.617021 (-675 3500);
PAINT SKYBLUE (-675 3500);
FORCEPROP 1 LAST VOLTAGE 4V
J 0
(-675 3700);
DISPLAY 0.617021 (-675 3700);
PAINT SKYBLUE (-675 3700);
FORCEPROP 1 LAST MATERIAL X6S
J 0
(-675 3600);
DISPLAY 0.617021 (-675 3600);
PAINT SKYBLUE (-675 3600);
FORCEPROP 2 LAST CDS_LOCATION C3D20
J 0
(-675 3800);
DISPLAY 0.617021 (-675 3800);
PAINT AQUA (-675 3800);
DISPLAY INVISIBLE (-675 3800);
FORCEPROP 2 LAST BOM_COST PROC
J 0
(-725 3700);
PAINT MONO (-725 3700);
DISPLAY INVISIBLE (-725 3700);
FORCEPROP 2 LAST CDS_LIB dev_discrete
J 0
(-725 3700);
PAINT ORANGE (-725 3700);
DISPLAY INVISIBLE (-725 3700);
FORCEPROP 2 LAST CDS_SEC 1
J 0
(-675 3900);
PAINT MONO (-675 3900);
DISPLAY INVISIBLE (-675 3900);
FORCEPROP 2 LAST $SEC 1
J 0
(-675 3900);
PAINT MONO (-675 3900);
DISPLAY INVISIBLE (-675 3900);
FORCEPROP 1 LAST PATH I207
J 0
(-675 3850);
DISPLAY 0.978723 (-675 3850);
PAINT WHITE (-675 3850);
DISPLAY INVISIBLE (-675 3850);
FORCEPROP 2 LAST ROOM PVCCIN_CPU1_DECAP_VR
J 0
(-675 3800);
PAINT ORANGE (-675 3800);
DISPLAY INVISIBLE (-675 3800);
FORCEPROP 1 LASTPIN (-725 3800) $PN 1
J 0
(-715 3780);
DISPLAY 0.787234 (-715 3780);
PAINT ORANGE (-715 3780);
DISPLAY INVISIBLE (-715 3780);
FORCEPROP 1 LASTPIN (-725 3600) $PN 2
J 0
(-715 3580);
DISPLAY 0.787234 (-715 3580);
PAINT ORANGE (-715 3580);
DISPLAY INVISIBLE (-715 3580);
FORCEADD CAP_A..1
(-950 3725);
FORCEPROP 1 LAST LOCATION C3D19
J 0
(-900 3825);
DISPLAY 0.617021 (-900 3825);
PAINT AQUA (-900 3825);
FORCEPROP 1 LAST PART_NUMBER E15431-004
J 0
(-900 3575);
DISPLAY 0.617021 (-900 3575);
PAINT BLUE (-900 3575);
FORCEPROP 1 LAST VALUE 22.0UF
J 0
(-900 3775);
DISPLAY 0.617021 (-900 3775);
PAINT SKYBLUE (-900 3775);
FORCEPROP 1 LAST TOLERANCE 20%
J 0
(-900 3675);
DISPLAY 0.617021 (-900 3675);
PAINT SKYBLUE (-900 3675);
FORCEPROP 1 LAST PACK_TYPE 0603V
J 0
(-900 3525);
DISPLAY 0.617021 (-900 3525);
PAINT SKYBLUE (-900 3525);
FORCEPROP 1 LAST VOLTAGE 4V
J 0
(-900 3725);
DISPLAY 0.617021 (-900 3725);
PAINT SKYBLUE (-900 3725);
FORCEPROP 1 LAST MATERIAL X6S
J 0
(-900 3625);
DISPLAY 0.617021 (-900 3625);
PAINT SKYBLUE (-900 3625);
FORCEPROP 2 LAST CDS_LOCATION C3D19
J 0
(-900 3825);
DISPLAY 0.617021 (-900 3825);
PAINT AQUA (-900 3825);
DISPLAY INVISIBLE (-900 3825);
FORCEPROP 2 LAST BOM_COST PROC
J 0
(-950 3725);
PAINT MONO (-950 3725);
DISPLAY INVISIBLE (-950 3725);
FORCEPROP 2 LAST CDS_LIB dev_discrete
J 0
(-950 3725);
PAINT ORANGE (-950 3725);
DISPLAY INVISIBLE (-950 3725);
FORCEPROP 2 LAST CDS_SEC 1
J 0
(-900 3925);
PAINT MONO (-900 3925);
DISPLAY INVISIBLE (-900 3925);
FORCEPROP 2 LAST $SEC 1
J 0
(-900 3925);
PAINT MONO (-900 3925);
DISPLAY INVISIBLE (-900 3925);
FORCEPROP 1 LAST PATH I208
J 0
(-900 3875);
DISPLAY 0.978723 (-900 3875);
PAINT WHITE (-900 3875);
DISPLAY INVISIBLE (-900 3875);
FORCEPROP 2 LAST ROOM PVCCIN_CPU1_DECAP_VR
J 0
(-900 3825);
PAINT ORANGE (-900 3825);
DISPLAY INVISIBLE (-900 3825);
FORCEPROP 1 LASTPIN (-950 3825) $PN 1
J 0
(-940 3805);
DISPLAY 0.787234 (-940 3805);
PAINT ORANGE (-940 3805);
DISPLAY INVISIBLE (-940 3805);
FORCEPROP 1 LASTPIN (-950 3625) $PN 2
J 0
(-940 3605);
DISPLAY 0.787234 (-940 3605);
PAINT ORANGE (-940 3605);
DISPLAY INVISIBLE (-940 3605);
FORCEADD VCC_CORE..1
(-1950 3975);
FORCEPROP 3 LASTPIN (-1950 3925) SIG_NAME PVCCMCP_CPU1\g
J 0
(-1940 3935);
DISPLAY 0.659574 (-1940 3935);
PAINT MONO (-1940 3935);
DISPLAY INVISIBLE (-1940 3935);
FORCEPROP 1 LAST HDL_POWER PVCCMCP_CPU1
J 1
(-1950 4025);
DISPLAY 0.617021 (-1950 4025);
PAINT GREEN (-1950 4025);
FORCEPROP 2 LAST CDS_LIB mstr_symbols
J 0
(-1950 3975);
PAINT ORANGE (-1950 3975);
DISPLAY INVISIBLE (-1950 3975);
FORCEPROP 1 LAST PATH I209
J 0
(-1900 4000);
DISPLAY 0.872340 (-1900 4000);
PAINT AQUA (-1900 4000);
DISPLAY INVISIBLE (-1900 4000);
FORCEADD GND..1
(-725 3400);
FORCEPROP 3 LASTPIN (-725 3450) SIG_NAME GND\g
J 0
(-715 3460);
DISPLAY 0.659574 (-715 3460);
PAINT MONO (-715 3460);
DISPLAY INVISIBLE (-715 3460);
FORCEPROP 1 LAST VOLTAGE 0
J 0
(-725 3400);
PAINT SKYBLUE (-725 3400);
DISPLAY INVISIBLE (-725 3400);
FORCEPROP 2 LAST CDS_LIB mstr_symbols
J 0
(-725 3400);
PAINT ORANGE (-725 3400);
DISPLAY INVISIBLE (-725 3400);
FORCEPROP 1 LAST SIZE 1B
J 0
(-650 3350);
DISPLAY 0.893617 (-650 3350);
PAINT GREEN (-650 3350);
DISPLAY INVISIBLE (-650 3350);
FORCEPROP 1 LAST BODY_TYPE PLUMBING
J 0
(-770 3357);
DISPLAY 0.340426 (-770 3357);
PAINT GREEN (-770 3357);
DISPLAY INVISIBLE (-770 3357);
FORCEPROP 1 LAST PATH I210
J 0
(-650 3400);
DISPLAY 0.872340 (-650 3400);
PAINT AQUA (-650 3400);
DISPLAY INVISIBLE (-650 3400);
FORCEPROP 2 LAST ROOM PVCCIN_CPU1_DECAP_VR
J 0
(-1275 3475);
PAINT ORANGE (-1275 3475);
DISPLAY INVISIBLE (-1275 3475);
FORCEPROP 1 LAST HDL_POWER GND
J 0
(-725 3550);
DISPLAY 0.893617 (-725 3550);
PAINT GREEN (-725 3550);
DISPLAY INVISIBLE (-725 3550);
FORCEADD CAP..1
(-975 2150);
FORCEPROP 1 LAST LOCATION C8P14
J 0
(-925 2250);
DISPLAY 0.617021 (-925 2250);
PAINT AQUA (-925 2250);
FORCEPROP 1 LAST PART_NUMBER C95333-006
R 1
J 0
(-1025 1975);
DISPLAY 0.617021 (-1025 1975);
PAINT BLUE (-1025 1975);
FORCEPROP 1 LAST VALUE 47UF
J 0
(-925 2200);
DISPLAY 0.617021 (-925 2200);
PAINT SKYBLUE (-925 2200);
FORCEPROP 1 LAST TOLERANCE 20%
J 0
(-925 2100);
DISPLAY 0.617021 (-925 2100);
PAINT SKYBLUE (-925 2100);
FORCEPROP 1 LAST PACK_TYPE 0805
J 0
(-925 2000);
DISPLAY 0.617021 (-925 2000);
PAINT SKYBLUE (-925 2000);
FORCEPROP 1 LAST VOLTAGE 4V
J 0
(-925 2150);
PAINT SKYBLUE (-925 2150);
DISPLAY INVISIBLE (-925 2150);
FORCEPROP 1 LAST MATERIAL X6S
J 0
(-925 2050);
PAINT SKYBLUE (-925 2050);
DISPLAY INVISIBLE (-925 2050);
FORCEPROP 2 LAST BOM_COST PROC
J 0
(-975 2150);
PAINT MONO (-975 2150);
DISPLAY INVISIBLE (-975 2150);
FORCEPROP 2 LAST CDS_LIB mstr_discrete
J 0
(-975 2150);
PAINT ORANGE (-975 2150);
DISPLAY INVISIBLE (-975 2150);
FORCEPROP 2 LAST CDS_SEC 1
J 0
(-925 2350);
PAINT MONO (-925 2350);
DISPLAY INVISIBLE (-925 2350);
FORCEPROP 2 LAST $SEC 1
J 0
(-925 2350);
PAINT MONO (-925 2350);
DISPLAY INVISIBLE (-925 2350);
FORCEPROP 2 LAST CDS_LOCATION C8P14
J 0
(-925 2250);
DISPLAY 0.617021 (-925 2250);
PAINT AQUA (-925 2250);
DISPLAY INVISIBLE (-925 2250);
FORCEPROP 1 LAST PATH I211
J 0
(-925 2300);
DISPLAY 0.978723 (-925 2300);
PAINT WHITE (-925 2300);
DISPLAY INVISIBLE (-925 2300);
FORCEPROP 2 LAST ROOM PVCCIN_CPU1_DECAP_VR
J 0
(-925 2250);
PAINT ORANGE (-925 2250);
DISPLAY INVISIBLE (-925 2250);
FORCEPROP 1 LASTPIN (-975 2050) $PN 2
J 0
(-965 2030);
DISPLAY 0.787234 (-965 2030);
PAINT ORANGE (-965 2030);
DISPLAY INVISIBLE (-965 2030);
FORCEPROP 1 LASTPIN (-975 2250) $PN 1
J 0
(-965 2230);
DISPLAY 0.787234 (-965 2230);
PAINT ORANGE (-965 2230);
DISPLAY INVISIBLE (-965 2230);
FORCEADD CAP..1
(-1225 2150);
FORCEPROP 1 LAST LOCATION C8P15
J 0
(-1175 2250);
DISPLAY 0.617021 (-1175 2250);
PAINT AQUA (-1175 2250);
FORCEPROP 1 LAST PART_NUMBER C95333-006
R 1
J 0
(-1275 1975);
DISPLAY 0.617021 (-1275 1975);
PAINT BLUE (-1275 1975);
FORCEPROP 1 LAST VALUE 47UF
J 0
(-1175 2200);
DISPLAY 0.617021 (-1175 2200);
PAINT SKYBLUE (-1175 2200);
FORCEPROP 1 LAST TOLERANCE 20%
J 0
(-1175 2100);
DISPLAY 0.617021 (-1175 2100);
PAINT SKYBLUE (-1175 2100);
FORCEPROP 1 LAST PACK_TYPE 0805
J 0
(-1175 2000);
DISPLAY 0.617021 (-1175 2000);
PAINT SKYBLUE (-1175 2000);
FORCEPROP 1 LAST VOLTAGE 4V
J 0
(-1175 2150);
PAINT SKYBLUE (-1175 2150);
DISPLAY INVISIBLE (-1175 2150);
FORCEPROP 1 LAST MATERIAL X6S
J 0
(-1175 2050);
PAINT SKYBLUE (-1175 2050);
DISPLAY INVISIBLE (-1175 2050);
FORCEPROP 2 LAST BOM_COST PROC
J 0
(-1225 2150);
PAINT MONO (-1225 2150);
DISPLAY INVISIBLE (-1225 2150);
FORCEPROP 2 LAST CDS_LIB mstr_discrete
J 0
(-1225 2150);
PAINT ORANGE (-1225 2150);
DISPLAY INVISIBLE (-1225 2150);
FORCEPROP 2 LAST CDS_SEC 1
J 0
(-1175 2350);
PAINT MONO (-1175 2350);
DISPLAY INVISIBLE (-1175 2350);
FORCEPROP 2 LAST $SEC 1
J 0
(-1175 2350);
PAINT MONO (-1175 2350);
DISPLAY INVISIBLE (-1175 2350);
FORCEPROP 2 LAST CDS_LOCATION C8P15
J 0
(-1175 2250);
DISPLAY 0.617021 (-1175 2250);
PAINT AQUA (-1175 2250);
DISPLAY INVISIBLE (-1175 2250);
FORCEPROP 1 LAST PATH I212
J 0
(-1175 2300);
DISPLAY 0.978723 (-1175 2300);
PAINT WHITE (-1175 2300);
DISPLAY INVISIBLE (-1175 2300);
FORCEPROP 2 LAST ROOM PVCCIN_CPU1_DECAP_VR
J 0
(-1175 2250);
PAINT ORANGE (-1175 2250);
DISPLAY INVISIBLE (-1175 2250);
FORCEPROP 1 LASTPIN (-1225 2050) $PN 2
J 0
(-1215 2030);
DISPLAY 0.787234 (-1215 2030);
PAINT ORANGE (-1215 2030);
DISPLAY INVISIBLE (-1215 2030);
FORCEPROP 1 LASTPIN (-1225 2250) $PN 1
J 0
(-1215 2230);
DISPLAY 0.787234 (-1215 2230);
PAINT ORANGE (-1215 2230);
DISPLAY INVISIBLE (-1215 2230);
FORCEADD CAP..1
(-500 2100);
FORCEPROP 1 LAST LOCATION C8P8
J 0
(-450 2200);
DISPLAY 0.617021 (-450 2200);
PAINT AQUA (-450 2200);
FORCEPROP 1 LAST PART_NUMBER C95333-006
J 0
(-450 2000);
DISPLAY 0.617021 (-450 2000);
PAINT BLUE (-450 2000);
FORCEPROP 1 LAST VALUE 47UF
J 0
(-450 2150);
DISPLAY 0.617021 (-450 2150);
PAINT SKYBLUE (-450 2150);
FORCEPROP 1 LAST TOLERANCE 20%
J 0
(-450 2050);
DISPLAY 0.617021 (-450 2050);
PAINT SKYBLUE (-450 2050);
FORCEPROP 1 LAST PACK_TYPE 0805
J 0
(-450 1950);
DISPLAY 0.617021 (-450 1950);
PAINT SKYBLUE (-450 1950);
FORCEPROP 1 LAST VOLTAGE 4V
J 0
(-450 2100);
PAINT SKYBLUE (-450 2100);
DISPLAY INVISIBLE (-450 2100);
FORCEPROP 1 LAST MATERIAL X6S
J 0
(-450 2000);
PAINT SKYBLUE (-450 2000);
DISPLAY INVISIBLE (-450 2000);
FORCEPROP 2 LAST CDS_LIB mstr_discrete
J 0
(-500 2100);
PAINT ORANGE (-500 2100);
DISPLAY INVISIBLE (-500 2100);
FORCEPROP 2 LAST BOM_COST PROC
J 0
(-500 2100);
PAINT MONO (-500 2100);
DISPLAY INVISIBLE (-500 2100);
FORCEPROP 2 LAST CDS_SEC 1
J 0
(-450 2300);
PAINT MONO (-450 2300);
DISPLAY INVISIBLE (-450 2300);
FORCEPROP 2 LAST $SEC 1
J 0
(-450 2300);
PAINT MONO (-450 2300);
DISPLAY INVISIBLE (-450 2300);
FORCEPROP 2 LAST CDS_LOCATION C8P8
J 0
(-450 2200);
DISPLAY 0.617021 (-450 2200);
PAINT AQUA (-450 2200);
DISPLAY INVISIBLE (-450 2200);
FORCEPROP 1 LAST PATH I213
J 0
(-450 2250);
DISPLAY 0.978723 (-450 2250);
PAINT WHITE (-450 2250);
DISPLAY INVISIBLE (-450 2250);
FORCEPROP 2 LAST ROOM PVCCIN_CPU1_DECAP_VR
J 0
(-450 2200);
PAINT ORANGE (-450 2200);
DISPLAY INVISIBLE (-450 2200);
FORCEPROP 1 LASTPIN (-500 2000) $PN 2
J 0
(-490 1980);
DISPLAY 0.787234 (-490 1980);
PAINT ORANGE (-490 1980);
DISPLAY INVISIBLE (-490 1980);
FORCEPROP 1 LASTPIN (-500 2200) $PN 1
J 0
(-490 2180);
DISPLAY 0.787234 (-490 2180);
PAINT ORANGE (-490 2180);
DISPLAY INVISIBLE (-490 2180);
FORCEADD CAP..1
(-700 2150);
FORCEPROP 1 LAST LOCATION C8P9
J 0
(-650 2250);
DISPLAY 0.617021 (-650 2250);
PAINT AQUA (-650 2250);
FORCEPROP 1 LAST PART_NUMBER C95333-006
R 1
J 0
(-750 1975);
DISPLAY 0.617021 (-750 1975);
PAINT BLUE (-750 1975);
FORCEPROP 1 LAST VALUE 47UF
J 0
(-650 2200);
DISPLAY 0.617021 (-650 2200);
PAINT SKYBLUE (-650 2200);
FORCEPROP 1 LAST TOLERANCE 20%
J 0
(-650 2100);
DISPLAY 0.617021 (-650 2100);
PAINT SKYBLUE (-650 2100);
FORCEPROP 1 LAST PACK_TYPE 0805
J 0
(-660 2035);
DISPLAY 0.617021 (-660 2035);
PAINT SKYBLUE (-660 2035);
FORCEPROP 1 LAST VOLTAGE 4V
J 0
(-650 2150);
PAINT SKYBLUE (-650 2150);
DISPLAY INVISIBLE (-650 2150);
FORCEPROP 1 LAST MATERIAL X6S
J 0
(-650 2050);
PAINT SKYBLUE (-650 2050);
DISPLAY INVISIBLE (-650 2050);
FORCEPROP 2 LAST BOM_COST PROC
J 0
(-700 2150);
PAINT MONO (-700 2150);
DISPLAY INVISIBLE (-700 2150);
FORCEPROP 2 LAST CDS_LIB mstr_discrete
J 0
(-700 2150);
PAINT ORANGE (-700 2150);
DISPLAY INVISIBLE (-700 2150);
FORCEPROP 2 LAST CDS_SEC 1
J 0
(-650 2350);
PAINT MONO (-650 2350);
DISPLAY INVISIBLE (-650 2350);
FORCEPROP 2 LAST $SEC 1
J 0
(-650 2350);
PAINT MONO (-650 2350);
DISPLAY INVISIBLE (-650 2350);
FORCEPROP 2 LAST CDS_LOCATION C8P9
J 0
(-650 2250);
DISPLAY 0.617021 (-650 2250);
PAINT AQUA (-650 2250);
DISPLAY INVISIBLE (-650 2250);
FORCEPROP 1 LAST PATH I214
J 0
(-650 2300);
DISPLAY 0.978723 (-650 2300);
PAINT WHITE (-650 2300);
DISPLAY INVISIBLE (-650 2300);
FORCEPROP 2 LAST ROOM PVCCIN_CPU1_DECAP_VR
J 0
(-650 2250);
PAINT ORANGE (-650 2250);
DISPLAY INVISIBLE (-650 2250);
FORCEPROP 1 LASTPIN (-700 2050) $PN 2
J 0
(-690 2030);
DISPLAY 0.787234 (-690 2030);
PAINT ORANGE (-690 2030);
DISPLAY INVISIBLE (-690 2030);
FORCEPROP 1 LASTPIN (-700 2250) $PN 1
J 0
(-690 2230);
DISPLAY 0.787234 (-690 2230);
PAINT ORANGE (-690 2230);
DISPLAY INVISIBLE (-690 2230);
FORCEADD CAP..1
(-6700 2200);
FORCEPROP 1 LAST LOCATION C7P19
J 0
(-6650 2300);
DISPLAY 0.617021 (-6650 2300);
PAINT AQUA (-6650 2300);
FORCEPROP 1 LAST PART_NUMBER C95333-006
R 1
J 0
(-6750 2025);
DISPLAY 0.617021 (-6750 2025);
PAINT BLUE (-6750 2025);
FORCEPROP 1 LAST VALUE 47UF
J 0
(-6650 2250);
DISPLAY 0.617021 (-6650 2250);
PAINT SKYBLUE (-6650 2250);
FORCEPROP 1 LAST TOLERANCE 20%
J 0
(-6650 2150);
DISPLAY 0.617021 (-6650 2150);
PAINT SKYBLUE (-6650 2150);
FORCEPROP 1 LAST PACK_TYPE 0805
J 0
(-6650 2050);
DISPLAY 0.617021 (-6650 2050);
PAINT SKYBLUE (-6650 2050);
FORCEPROP 1 LAST VOLTAGE 4V
J 0
(-6650 2200);
PAINT SKYBLUE (-6650 2200);
DISPLAY INVISIBLE (-6650 2200);
FORCEPROP 1 LAST MATERIAL X6S
J 0
(-6650 2100);
PAINT SKYBLUE (-6650 2100);
DISPLAY INVISIBLE (-6650 2100);
FORCEPROP 2 LAST CDS_LIB mstr_discrete
J 0
(-6700 2200);
PAINT ORANGE (-6700 2200);
DISPLAY INVISIBLE (-6700 2200);
FORCEPROP 2 LAST BOM_COST PROC
J 0
(-6700 2200);
PAINT MONO (-6700 2200);
DISPLAY INVISIBLE (-6700 2200);
FORCEPROP 2 LAST CDS_SEC 1
J 0
(-6650 2400);
PAINT MONO (-6650 2400);
DISPLAY INVISIBLE (-6650 2400);
FORCEPROP 2 LAST $SEC 1
J 0
(-6650 2400);
PAINT MONO (-6650 2400);
DISPLAY INVISIBLE (-6650 2400);
FORCEPROP 2 LAST CDS_LOCATION C7P19
J 0
(-6650 2300);
DISPLAY 0.617021 (-6650 2300);
PAINT AQUA (-6650 2300);
DISPLAY INVISIBLE (-6650 2300);
FORCEPROP 1 LAST PATH I215
J 0
(-6650 2350);
DISPLAY 0.978723 (-6650 2350);
PAINT WHITE (-6650 2350);
DISPLAY INVISIBLE (-6650 2350);
FORCEPROP 2 LAST ROOM PVCCIN_CPU1_DECAP_VR
J 0
(-6650 2300);
PAINT ORANGE (-6650 2300);
DISPLAY INVISIBLE (-6650 2300);
FORCEPROP 1 LASTPIN (-6700 2100) $PN 2
J 0
(-6690 2080);
DISPLAY 0.787234 (-6690 2080);
PAINT ORANGE (-6690 2080);
DISPLAY INVISIBLE (-6690 2080);
FORCEPROP 1 LASTPIN (-6700 2300) $PN 1
J 0
(-6690 2280);
DISPLAY 0.787234 (-6690 2280);
PAINT ORANGE (-6690 2280);
DISPLAY INVISIBLE (-6690 2280);
FORCEADD CAP..1
(-6350 2200);
FORCEPROP 1 LAST LOCATION C8P32
J 0
(-6300 2300);
DISPLAY 0.617021 (-6300 2300);
PAINT AQUA (-6300 2300);
FORCEPROP 1 LAST PART_NUMBER C95333-006
R 1
J 0
(-6400 2025);
DISPLAY 0.617021 (-6400 2025);
PAINT BLUE (-6400 2025);
FORCEPROP 1 LAST VALUE 47UF
J 0
(-6300 2250);
DISPLAY 0.617021 (-6300 2250);
PAINT SKYBLUE (-6300 2250);
FORCEPROP 1 LAST TOLERANCE 20%
J 0
(-6300 2150);
DISPLAY 0.617021 (-6300 2150);
PAINT SKYBLUE (-6300 2150);
FORCEPROP 1 LAST PACK_TYPE 0805
J 0
(-6300 2050);
DISPLAY 0.617021 (-6300 2050);
PAINT SKYBLUE (-6300 2050);
FORCEPROP 1 LAST VOLTAGE 4V
J 0
(-6300 2200);
PAINT SKYBLUE (-6300 2200);
DISPLAY INVISIBLE (-6300 2200);
FORCEPROP 1 LAST MATERIAL X6S
J 0
(-6300 2100);
PAINT SKYBLUE (-6300 2100);
DISPLAY INVISIBLE (-6300 2100);
FORCEPROP 2 LAST CDS_LIB mstr_discrete
J 0
(-6350 2200);
PAINT ORANGE (-6350 2200);
DISPLAY INVISIBLE (-6350 2200);
FORCEPROP 2 LAST BOM_COST PROC
J 0
(-6350 2200);
PAINT MONO (-6350 2200);
DISPLAY INVISIBLE (-6350 2200);
FORCEPROP 2 LAST CDS_SEC 1
J 0
(-6300 2400);
PAINT MONO (-6300 2400);
DISPLAY INVISIBLE (-6300 2400);
FORCEPROP 2 LAST $SEC 1
J 0
(-6300 2400);
PAINT MONO (-6300 2400);
DISPLAY INVISIBLE (-6300 2400);
FORCEPROP 2 LAST CDS_LOCATION C8P32
J 0
(-6300 2300);
DISPLAY 0.617021 (-6300 2300);
PAINT AQUA (-6300 2300);
DISPLAY INVISIBLE (-6300 2300);
FORCEPROP 1 LAST PATH I216
J 0
(-6300 2350);
DISPLAY 0.978723 (-6300 2350);
PAINT WHITE (-6300 2350);
DISPLAY INVISIBLE (-6300 2350);
FORCEPROP 2 LAST ROOM PVCCIN_CPU1_DECAP_VR
J 0
(-6300 2300);
PAINT ORANGE (-6300 2300);
DISPLAY INVISIBLE (-6300 2300);
FORCEPROP 1 LASTPIN (-6350 2100) $PN 2
J 0
(-6340 2080);
DISPLAY 0.787234 (-6340 2080);
PAINT ORANGE (-6340 2080);
DISPLAY INVISIBLE (-6340 2080);
FORCEPROP 1 LASTPIN (-6350 2300) $PN 1
J 0
(-6340 2280);
DISPLAY 0.787234 (-6340 2280);
PAINT ORANGE (-6340 2280);
DISPLAY INVISIBLE (-6340 2280);
FORCEADD CAP..1
(-7725 900);
FORCEPROP 1 LAST LOCATION C8P24
J 0
(-7675 1000);
DISPLAY 0.617021 (-7675 1000);
PAINT AQUA (-7675 1000);
FORCEPROP 1 LAST PART_NUMBER C95333-006
R 1
J 0
(-7775 725);
DISPLAY 0.617021 (-7775 725);
PAINT BLUE (-7775 725);
FORCEPROP 1 LAST VALUE 47UF
J 0
(-7675 950);
DISPLAY 0.617021 (-7675 950);
PAINT SKYBLUE (-7675 950);
FORCEPROP 1 LAST TOLERANCE 20%
J 0
(-7675 850);
DISPLAY 0.617021 (-7675 850);
PAINT SKYBLUE (-7675 850);
FORCEPROP 1 LAST PACK_TYPE 0805
J 0
(-7675 750);
DISPLAY 0.617021 (-7675 750);
PAINT SKYBLUE (-7675 750);
FORCEPROP 1 LAST VOLTAGE 4V
J 0
(-7675 900);
PAINT SKYBLUE (-7675 900);
DISPLAY INVISIBLE (-7675 900);
FORCEPROP 1 LAST MATERIAL X6S
J 0
(-7675 800);
PAINT SKYBLUE (-7675 800);
DISPLAY INVISIBLE (-7675 800);
FORCEPROP 2 LAST CDS_LIB mstr_discrete
J 0
(-7725 900);
PAINT ORANGE (-7725 900);
DISPLAY INVISIBLE (-7725 900);
FORCEPROP 2 LAST BOM_COST PROC
J 0
(-7725 900);
PAINT MONO (-7725 900);
DISPLAY INVISIBLE (-7725 900);
FORCEPROP 2 LAST CDS_SEC 1
J 0
(-7675 1100);
PAINT MONO (-7675 1100);
DISPLAY INVISIBLE (-7675 1100);
FORCEPROP 2 LAST $SEC 1
J 0
(-7675 1100);
PAINT MONO (-7675 1100);
DISPLAY INVISIBLE (-7675 1100);
FORCEPROP 2 LAST CDS_LOCATION C8P24
J 0
(-7675 1000);
DISPLAY 0.617021 (-7675 1000);
PAINT AQUA (-7675 1000);
DISPLAY INVISIBLE (-7675 1000);
FORCEPROP 1 LAST PATH I217
J 0
(-7675 1050);
DISPLAY 0.978723 (-7675 1050);
PAINT WHITE (-7675 1050);
DISPLAY INVISIBLE (-7675 1050);
FORCEPROP 2 LAST ROOM PVCCIN_CPU1_DECAP_VR
J 0
(-7675 1000);
PAINT ORANGE (-7675 1000);
DISPLAY INVISIBLE (-7675 1000);
FORCEPROP 1 LASTPIN (-7725 800) $PN 2
J 0
(-7715 780);
DISPLAY 0.787234 (-7715 780);
PAINT ORANGE (-7715 780);
DISPLAY INVISIBLE (-7715 780);
FORCEPROP 1 LASTPIN (-7725 1000) $PN 1
J 0
(-7715 980);
DISPLAY 0.787234 (-7715 980);
PAINT ORANGE (-7715 980);
DISPLAY INVISIBLE (-7715 980);
FORCEADD CAP..1
(-5150 2200);
FORCEPROP 1 LAST LOCATION C7P20
J 0
(-5100 2300);
DISPLAY 0.617021 (-5100 2300);
PAINT AQUA (-5100 2300);
FORCEPROP 1 LAST PART_NUMBER C95333-006
R 1
J 0
(-5200 2025);
DISPLAY 0.617021 (-5200 2025);
PAINT BLUE (-5200 2025);
FORCEPROP 1 LAST VALUE 47UF
J 0
(-5100 2250);
DISPLAY 0.617021 (-5100 2250);
PAINT SKYBLUE (-5100 2250);
FORCEPROP 1 LAST TOLERANCE 20%
J 0
(-5100 2150);
DISPLAY 0.617021 (-5100 2150);
PAINT SKYBLUE (-5100 2150);
FORCEPROP 1 LAST PACK_TYPE 0805
J 0
(-5100 2050);
DISPLAY 0.617021 (-5100 2050);
PAINT SKYBLUE (-5100 2050);
FORCEPROP 1 LAST VOLTAGE 4V
J 0
(-5100 2200);
PAINT SKYBLUE (-5100 2200);
DISPLAY INVISIBLE (-5100 2200);
FORCEPROP 1 LAST MATERIAL X6S
J 0
(-5100 2100);
PAINT SKYBLUE (-5100 2100);
DISPLAY INVISIBLE (-5100 2100);
FORCEPROP 2 LAST BOM_COST PROC
J 0
(-5150 2200);
PAINT MONO (-5150 2200);
DISPLAY INVISIBLE (-5150 2200);
FORCEPROP 2 LAST CDS_LIB mstr_discrete
J 0
(-5150 2200);
PAINT ORANGE (-5150 2200);
DISPLAY INVISIBLE (-5150 2200);
FORCEPROP 2 LAST CDS_SEC 1
J 0
(-5100 2400);
PAINT MONO (-5100 2400);
DISPLAY INVISIBLE (-5100 2400);
FORCEPROP 2 LAST $SEC 1
J 0
(-5100 2400);
PAINT MONO (-5100 2400);
DISPLAY INVISIBLE (-5100 2400);
FORCEPROP 2 LAST CDS_LOCATION C7P20
J 0
(-5100 2300);
DISPLAY 0.617021 (-5100 2300);
PAINT AQUA (-5100 2300);
DISPLAY INVISIBLE (-5100 2300);
FORCEPROP 1 LAST PATH I218
J 0
(-5100 2350);
DISPLAY 0.978723 (-5100 2350);
PAINT WHITE (-5100 2350);
DISPLAY INVISIBLE (-5100 2350);
FORCEPROP 2 LAST ROOM PVCCIN_CPU1_DECAP_VR
J 0
(-5100 2300);
PAINT ORANGE (-5100 2300);
DISPLAY INVISIBLE (-5100 2300);
FORCEPROP 1 LASTPIN (-5150 2100) $PN 2
J 0
(-5140 2080);
DISPLAY 0.787234 (-5140 2080);
PAINT ORANGE (-5140 2080);
DISPLAY INVISIBLE (-5140 2080);
FORCEPROP 1 LASTPIN (-5150 2300) $PN 1
J 0
(-5140 2280);
DISPLAY 0.787234 (-5140 2280);
PAINT ORANGE (-5140 2280);
DISPLAY INVISIBLE (-5140 2280);
FORCEADD CAP..1
(-1750 2125);
FORCEPROP 1 LAST LOCATION C7P6
J 0
(-1700 2225);
DISPLAY 0.617021 (-1700 2225);
PAINT AQUA (-1700 2225);
FORCEPROP 1 LAST PART_NUMBER C95333-006
R 1
J 0
(-1800 1950);
DISPLAY 0.617021 (-1800 1950);
PAINT BLUE (-1800 1950);
FORCEPROP 1 LAST VALUE 47UF
J 0
(-1700 2175);
DISPLAY 0.617021 (-1700 2175);
PAINT SKYBLUE (-1700 2175);
FORCEPROP 1 LAST TOLERANCE 20%
J 0
(-1700 2075);
DISPLAY 0.617021 (-1700 2075);
PAINT SKYBLUE (-1700 2075);
FORCEPROP 1 LAST PACK_TYPE 0805
J 0
(-1700 1975);
DISPLAY 0.617021 (-1700 1975);
PAINT SKYBLUE (-1700 1975);
FORCEPROP 1 LASTPIN (-1750 2025) $PN 2
J 0
(-1740 2005);
DISPLAY 0.617021 (-1740 2005);
PAINT GREEN (-1740 2005);
FORCEPROP 1 LASTPIN (-1750 2225) $PN 1
J 0
(-1740 2205);
DISPLAY 0.617021 (-1740 2205);
PAINT GREEN (-1740 2205);
FORCEPROP 1 LAST VOLTAGE 4V
J 0
(-1700 2125);
PAINT SKYBLUE (-1700 2125);
DISPLAY INVISIBLE (-1700 2125);
FORCEPROP 1 LAST MATERIAL X6S
J 0
(-1700 2025);
PAINT SKYBLUE (-1700 2025);
DISPLAY INVISIBLE (-1700 2025);
FORCEPROP 2 LAST CDS_LIB mstr_discrete
J 0
(-1750 2125);
PAINT ORANGE (-1750 2125);
DISPLAY INVISIBLE (-1750 2125);
FORCEPROP 2 LAST BOM_COST PROC
J 0
(-1750 2125);
PAINT MONO (-1750 2125);
DISPLAY INVISIBLE (-1750 2125);
FORCEPROP 2 LAST CDS_SEC 1
J 0
(-1700 2325);
DISPLAY 1.021277 (-1700 2325);
PAINT ORANGE (-1700 2325);
DISPLAY INVISIBLE (-1700 2325);
FORCEPROP 2 LAST $SEC 1
J 0
(-1700 2325);
DISPLAY 0.680851 (-1700 2325);
PAINT MONO (-1700 2325);
DISPLAY INVISIBLE (-1700 2325);
FORCEPROP 2 LAST CDS_LOCATION C7P6
J 0
(-1700 2225);
DISPLAY 0.617021 (-1700 2225);
PAINT AQUA (-1700 2225);
DISPLAY INVISIBLE (-1700 2225);
FORCEPROP 1 LAST PATH I23
J 0
(-1700 2275);
DISPLAY 0.978723 (-1700 2275);
PAINT WHITE (-1700 2275);
DISPLAY INVISIBLE (-1700 2275);
FORCEPROP 2 LAST ROOM PVCCIN_CPU1_DECAP_VR
J 0
(-1700 2225);
PAINT ORANGE (-1700 2225);
DISPLAY INVISIBLE (-1700 2225);
FORCEADD GND..1
(-500 1725);
FORCEPROP 3 LASTPIN (-500 1775) SIG_NAME GND\g
J 0
(-490 1785);
DISPLAY 0.659574 (-490 1785);
PAINT MONO (-490 1785);
DISPLAY INVISIBLE (-490 1785);
FORCEPROP 1 LAST VOLTAGE 0
J 0
(-500 1725);
PAINT SKYBLUE (-500 1725);
DISPLAY INVISIBLE (-500 1725);
FORCEPROP 2 LAST CDS_LIB mstr_symbols
J 0
(-500 1725);
PAINT ORANGE (-500 1725);
DISPLAY INVISIBLE (-500 1725);
FORCEPROP 1 LAST SIZE 1B
J 0
(-425 1675);
DISPLAY 0.893617 (-425 1675);
PAINT GREEN (-425 1675);
DISPLAY INVISIBLE (-425 1675);
FORCEPROP 1 LAST BODY_TYPE PLUMBING
J 0
(-545 1682);
DISPLAY 0.340426 (-545 1682);
PAINT GREEN (-545 1682);
DISPLAY INVISIBLE (-545 1682);
FORCEPROP 1 LAST PATH I24
J 0
(-425 1725);
DISPLAY 0.872340 (-425 1725);
PAINT AQUA (-425 1725);
DISPLAY INVISIBLE (-425 1725);
FORCEPROP 2 LAST ROOM PVCCIN_CPU1_DECAP_VR
J 0
(-1050 1800);
PAINT ORANGE (-1050 1800);
DISPLAY INVISIBLE (-1050 1800);
FORCEPROP 1 LAST HDL_POWER GND
J 0
(-500 1875);
DISPLAY 0.893617 (-500 1875);
PAINT GREEN (-500 1875);
DISPLAY INVISIBLE (-500 1875);
FORCEADD CAP..1
(-2025 2150);
FORCEPROP 1 LAST LOCATION C7P13
J 0
(-1975 2250);
DISPLAY 0.617021 (-1975 2250);
PAINT AQUA (-1975 2250);
FORCEPROP 1 LAST PART_NUMBER C95333-006
R 1
J 0
(-2075 1975);
DISPLAY 0.617021 (-2075 1975);
PAINT BLUE (-2075 1975);
FORCEPROP 1 LAST VALUE 47UF
J 0
(-1975 2200);
DISPLAY 0.617021 (-1975 2200);
PAINT SKYBLUE (-1975 2200);
FORCEPROP 1 LAST TOLERANCE 20%
J 0
(-1975 2100);
DISPLAY 0.617021 (-1975 2100);
PAINT SKYBLUE (-1975 2100);
FORCEPROP 1 LAST PACK_TYPE 0805
J 0
(-1975 2000);
DISPLAY 0.617021 (-1975 2000);
PAINT SKYBLUE (-1975 2000);
FORCEPROP 1 LASTPIN (-2025 2050) $PN 2
J 0
(-2015 2030);
DISPLAY 0.617021 (-2015 2030);
PAINT GREEN (-2015 2030);
FORCEPROP 1 LASTPIN (-2025 2250) $PN 1
J 0
(-2015 2230);
DISPLAY 0.617021 (-2015 2230);
PAINT GREEN (-2015 2230);
FORCEPROP 1 LAST VOLTAGE 4V
J 0
(-1975 2150);
PAINT SKYBLUE (-1975 2150);
DISPLAY INVISIBLE (-1975 2150);
FORCEPROP 1 LAST MATERIAL X6S
J 0
(-1975 2050);
PAINT SKYBLUE (-1975 2050);
DISPLAY INVISIBLE (-1975 2050);
FORCEPROP 2 LAST CDS_LIB mstr_discrete
J 0
(-2025 2150);
PAINT ORANGE (-2025 2150);
DISPLAY INVISIBLE (-2025 2150);
FORCEPROP 2 LAST BOM_COST PROC
J 0
(-2025 2150);
PAINT MONO (-2025 2150);
DISPLAY INVISIBLE (-2025 2150);
FORCEPROP 2 LAST CDS_SEC 1
J 0
(-1975 2350);
DISPLAY 1.021277 (-1975 2350);
PAINT ORANGE (-1975 2350);
DISPLAY INVISIBLE (-1975 2350);
FORCEPROP 2 LAST $SEC 1
J 0
(-1975 2350);
DISPLAY 0.680851 (-1975 2350);
PAINT MONO (-1975 2350);
DISPLAY INVISIBLE (-1975 2350);
FORCEPROP 2 LAST CDS_LOCATION C7P13
J 0
(-1975 2250);
DISPLAY 0.617021 (-1975 2250);
PAINT AQUA (-1975 2250);
DISPLAY INVISIBLE (-1975 2250);
FORCEPROP 1 LAST PATH I25
J 0
(-1975 2300);
DISPLAY 0.978723 (-1975 2300);
PAINT WHITE (-1975 2300);
DISPLAY INVISIBLE (-1975 2300);
FORCEPROP 2 LAST ROOM PVCCIN_CPU1_DECAP_VR
J 0
(-1975 2250);
PAINT ORANGE (-1975 2250);
DISPLAY INVISIBLE (-1975 2250);
FORCEADD CAP..1
(-2325 2150);
FORCEPROP 1 LAST LOCATION C7P10
J 0
(-2275 2250);
DISPLAY 0.617021 (-2275 2250);
PAINT AQUA (-2275 2250);
FORCEPROP 1 LAST PART_NUMBER C95333-006
R 1
J 0
(-2375 1975);
DISPLAY 0.617021 (-2375 1975);
PAINT BLUE (-2375 1975);
FORCEPROP 1 LAST VALUE 47UF
J 0
(-2275 2200);
DISPLAY 0.617021 (-2275 2200);
PAINT SKYBLUE (-2275 2200);
FORCEPROP 1 LAST TOLERANCE 20%
J 0
(-2275 2100);
DISPLAY 0.617021 (-2275 2100);
PAINT SKYBLUE (-2275 2100);
FORCEPROP 1 LAST PACK_TYPE 0805
J 0
(-2275 2000);
DISPLAY 0.617021 (-2275 2000);
PAINT SKYBLUE (-2275 2000);
FORCEPROP 1 LASTPIN (-2325 2050) $PN 2
J 0
(-2315 2030);
DISPLAY 0.617021 (-2315 2030);
PAINT GREEN (-2315 2030);
FORCEPROP 1 LASTPIN (-2325 2250) $PN 1
J 0
(-2315 2230);
DISPLAY 0.617021 (-2315 2230);
PAINT GREEN (-2315 2230);
FORCEPROP 1 LAST VOLTAGE 4V
J 0
(-2275 2150);
PAINT SKYBLUE (-2275 2150);
DISPLAY INVISIBLE (-2275 2150);
FORCEPROP 1 LAST MATERIAL X6S
J 0
(-2275 2050);
PAINT SKYBLUE (-2275 2050);
DISPLAY INVISIBLE (-2275 2050);
FORCEPROP 2 LAST CDS_LIB mstr_discrete
J 0
(-2325 2150);
PAINT ORANGE (-2325 2150);
DISPLAY INVISIBLE (-2325 2150);
FORCEPROP 2 LAST BOM_COST PROC
J 0
(-2325 2150);
PAINT MONO (-2325 2150);
DISPLAY INVISIBLE (-2325 2150);
FORCEPROP 2 LAST CDS_SEC 1
J 0
(-2275 2350);
DISPLAY 1.021277 (-2275 2350);
PAINT ORANGE (-2275 2350);
DISPLAY INVISIBLE (-2275 2350);
FORCEPROP 2 LAST $SEC 1
J 0
(-2275 2350);
DISPLAY 0.680851 (-2275 2350);
PAINT MONO (-2275 2350);
DISPLAY INVISIBLE (-2275 2350);
FORCEPROP 2 LAST CDS_LOCATION C7P10
J 0
(-2275 2250);
DISPLAY 0.617021 (-2275 2250);
PAINT AQUA (-2275 2250);
DISPLAY INVISIBLE (-2275 2250);
FORCEPROP 1 LAST PATH I26
J 0
(-2275 2300);
DISPLAY 0.978723 (-2275 2300);
PAINT WHITE (-2275 2300);
DISPLAY INVISIBLE (-2275 2300);
FORCEPROP 2 LAST ROOM PVCCIN_CPU1_DECAP_VR
J 0
(-2275 2250);
PAINT ORANGE (-2275 2250);
DISPLAY INVISIBLE (-2275 2250);
FORCEADD CAP..1
(-2625 2150);
FORCEPROP 1 LAST LOCATION C7P7
J 0
(-2575 2250);
DISPLAY 0.617021 (-2575 2250);
PAINT AQUA (-2575 2250);
FORCEPROP 1 LAST PART_NUMBER C95333-006
R 1
J 0
(-2675 1975);
DISPLAY 0.617021 (-2675 1975);
PAINT BLUE (-2675 1975);
FORCEPROP 1 LAST VALUE 47UF
J 0
(-2575 2200);
DISPLAY 0.617021 (-2575 2200);
PAINT SKYBLUE (-2575 2200);
FORCEPROP 1 LAST TOLERANCE 20%
J 0
(-2575 2100);
DISPLAY 0.617021 (-2575 2100);
PAINT SKYBLUE (-2575 2100);
FORCEPROP 1 LAST PACK_TYPE 0805
J 0
(-2575 2000);
DISPLAY 0.617021 (-2575 2000);
PAINT SKYBLUE (-2575 2000);
FORCEPROP 1 LASTPIN (-2625 2050) $PN 2
J 0
(-2615 2030);
DISPLAY 0.617021 (-2615 2030);
PAINT GREEN (-2615 2030);
FORCEPROP 1 LASTPIN (-2625 2250) $PN 1
J 0
(-2615 2230);
DISPLAY 0.617021 (-2615 2230);
PAINT GREEN (-2615 2230);
FORCEPROP 1 LAST VOLTAGE 4V
J 0
(-2575 2150);
PAINT SKYBLUE (-2575 2150);
DISPLAY INVISIBLE (-2575 2150);
FORCEPROP 1 LAST MATERIAL X6S
J 0
(-2575 2050);
PAINT SKYBLUE (-2575 2050);
DISPLAY INVISIBLE (-2575 2050);
FORCEPROP 2 LAST CDS_LIB mstr_discrete
J 0
(-2625 2150);
PAINT ORANGE (-2625 2150);
DISPLAY INVISIBLE (-2625 2150);
FORCEPROP 2 LAST BOM_COST PROC
J 0
(-2625 2150);
PAINT MONO (-2625 2150);
DISPLAY INVISIBLE (-2625 2150);
FORCEPROP 2 LAST CDS_SEC 1
J 0
(-2575 2350);
DISPLAY 1.021277 (-2575 2350);
PAINT ORANGE (-2575 2350);
DISPLAY INVISIBLE (-2575 2350);
FORCEPROP 2 LAST $SEC 1
J 0
(-2575 2350);
DISPLAY 0.680851 (-2575 2350);
PAINT MONO (-2575 2350);
DISPLAY INVISIBLE (-2575 2350);
FORCEPROP 2 LAST CDS_LOCATION C7P7
J 0
(-2575 2250);
DISPLAY 0.617021 (-2575 2250);
PAINT AQUA (-2575 2250);
DISPLAY INVISIBLE (-2575 2250);
FORCEPROP 1 LAST PATH I27
J 0
(-2575 2300);
DISPLAY 0.978723 (-2575 2300);
PAINT WHITE (-2575 2300);
DISPLAY INVISIBLE (-2575 2300);
FORCEPROP 2 LAST ROOM PVCCIN_CPU1_DECAP_VR
J 0
(-2550 2250);
PAINT ORANGE (-2550 2250);
DISPLAY INVISIBLE (-2550 2250);
FORCEADD CAP..1
(-2925 2150);
FORCEPROP 1 LAST LOCATION C8P22
J 0
(-2875 2250);
DISPLAY 0.617021 (-2875 2250);
PAINT AQUA (-2875 2250);
FORCEPROP 1 LAST PART_NUMBER C95333-006
R 1
J 0
(-2975 1975);
DISPLAY 0.617021 (-2975 1975);
PAINT BLUE (-2975 1975);
FORCEPROP 1 LAST VALUE 47UF
J 0
(-2875 2200);
DISPLAY 0.617021 (-2875 2200);
PAINT SKYBLUE (-2875 2200);
FORCEPROP 1 LAST TOLERANCE 20%
J 0
(-2875 2100);
DISPLAY 0.617021 (-2875 2100);
PAINT SKYBLUE (-2875 2100);
FORCEPROP 1 LAST PACK_TYPE 0805
J 0
(-2875 2000);
DISPLAY 0.617021 (-2875 2000);
PAINT SKYBLUE (-2875 2000);
FORCEPROP 1 LASTPIN (-2925 2050) $PN 2
J 0
(-2915 2030);
DISPLAY 0.617021 (-2915 2030);
PAINT GREEN (-2915 2030);
FORCEPROP 1 LASTPIN (-2925 2250) $PN 1
J 0
(-2915 2230);
DISPLAY 0.617021 (-2915 2230);
PAINT GREEN (-2915 2230);
FORCEPROP 1 LAST VOLTAGE 4V
J 0
(-2875 2150);
PAINT SKYBLUE (-2875 2150);
DISPLAY INVISIBLE (-2875 2150);
FORCEPROP 1 LAST MATERIAL X6S
J 0
(-2875 2050);
PAINT SKYBLUE (-2875 2050);
DISPLAY INVISIBLE (-2875 2050);
FORCEPROP 2 LAST CDS_LIB mstr_discrete
J 0
(-2925 2150);
PAINT ORANGE (-2925 2150);
DISPLAY INVISIBLE (-2925 2150);
FORCEPROP 2 LAST BOM_COST PROC
J 0
(-2925 2150);
PAINT MONO (-2925 2150);
DISPLAY INVISIBLE (-2925 2150);
FORCEPROP 2 LAST CDS_SEC 1
J 0
(-2875 2350);
DISPLAY 1.021277 (-2875 2350);
PAINT ORANGE (-2875 2350);
DISPLAY INVISIBLE (-2875 2350);
FORCEPROP 2 LAST $SEC 1
J 0
(-2875 2350);
DISPLAY 0.680851 (-2875 2350);
PAINT MONO (-2875 2350);
DISPLAY INVISIBLE (-2875 2350);
FORCEPROP 2 LAST CDS_LOCATION C8P22
J 0
(-2875 2250);
DISPLAY 0.617021 (-2875 2250);
PAINT AQUA (-2875 2250);
DISPLAY INVISIBLE (-2875 2250);
FORCEPROP 1 LAST PATH I28
J 0
(-2875 2300);
DISPLAY 0.978723 (-2875 2300);
PAINT WHITE (-2875 2300);
DISPLAY INVISIBLE (-2875 2300);
FORCEPROP 2 LAST ROOM PVCCIN_CPU1_DECAP_VR
J 0
(-2875 2250);
PAINT ORANGE (-2875 2250);
DISPLAY INVISIBLE (-2875 2250);
FORCEADD CAP..1
(-2625 925);
FORCEPROP 1 LAST LOCATION C7P17
J 0
(-2575 1025);
DISPLAY 0.617021 (-2575 1025);
PAINT AQUA (-2575 1025);
FORCEPROP 1 LAST PART_NUMBER C95333-006
J 0
(-2600 825);
DISPLAY 0.617021 (-2600 825);
PAINT BLUE (-2600 825);
FORCEPROP 1 LAST VALUE 47UF
J 0
(-2575 975);
DISPLAY 0.617021 (-2575 975);
PAINT SKYBLUE (-2575 975);
FORCEPROP 1 LAST TOLERANCE 20%
J 0
(-2575 875);
DISPLAY 0.617021 (-2575 875);
PAINT SKYBLUE (-2575 875);
FORCEPROP 1 LAST PACK_TYPE 0805
J 0
(-2575 775);
DISPLAY 0.617021 (-2575 775);
PAINT SKYBLUE (-2575 775);
FORCEPROP 1 LASTPIN (-2625 825) $PN 2
J 0
(-2615 805);
DISPLAY 0.617021 (-2615 805);
PAINT ORANGE (-2615 805);
FORCEPROP 1 LASTPIN (-2625 1025) $PN 1
J 0
(-2615 1005);
DISPLAY 0.617021 (-2615 1005);
PAINT ORANGE (-2615 1005);
FORCEPROP 1 LAST VOLTAGE 4V
J 0
(-2575 925);
PAINT SKYBLUE (-2575 925);
DISPLAY INVISIBLE (-2575 925);
FORCEPROP 1 LAST MATERIAL X6S
J 0
(-2575 825);
PAINT SKYBLUE (-2575 825);
DISPLAY INVISIBLE (-2575 825);
FORCEPROP 2 LAST BOM_COST PROC
J 0
(-2625 925);
PAINT MONO (-2625 925);
DISPLAY INVISIBLE (-2625 925);
FORCEPROP 2 LAST CDS_LIB mstr_discrete
J 0
(-2625 925);
PAINT ORANGE (-2625 925);
DISPLAY INVISIBLE (-2625 925);
FORCEPROP 2 LAST CDS_SEC 1
J 0
(-2565 1145);
PAINT MONO (-2565 1145);
DISPLAY INVISIBLE (-2565 1145);
FORCEPROP 2 LAST $SEC 1
J 0
(-2565 1145);
PAINT MONO (-2565 1145);
DISPLAY INVISIBLE (-2565 1145);
FORCEPROP 2 LAST CDS_LOCATION C7P17
J 0
(-2575 1025);
DISPLAY 0.617021 (-2575 1025);
PAINT AQUA (-2575 1025);
DISPLAY INVISIBLE (-2575 1025);
FORCEPROP 1 LAST PATH I29
J 0
(-2575 1075);
DISPLAY 0.978723 (-2575 1075);
PAINT WHITE (-2575 1075);
DISPLAY INVISIBLE (-2575 1075);
FORCEPROP 2 LAST ROOM PVCCIN_CPU1_DECAP_VR
J 0
(-2575 1025);
PAINT ORANGE (-2575 1025);
DISPLAY INVISIBLE (-2575 1025);
FORCEADD CAP_A..1
(-1600 4450);
FORCEPROP 1 LAST LOCATION C3D5
J 0
(-1550 4550);
DISPLAY 0.617021 (-1550 4550);
PAINT AQUA (-1550 4550);
FORCEPROP 1 LAST PART_NUMBER E15431-004
J 0
(-1550 4300);
DISPLAY 0.617021 (-1550 4300);
PAINT BLUE (-1550 4300);
FORCEPROP 1 LAST VALUE 22.0UF
J 0
(-1550 4500);
DISPLAY 0.617021 (-1550 4500);
PAINT SKYBLUE (-1550 4500);
FORCEPROP 1 LAST TOLERANCE 20%
J 0
(-1550 4400);
DISPLAY 0.617021 (-1550 4400);
PAINT SKYBLUE (-1550 4400);
FORCEPROP 1 LAST PACK_TYPE 0603V
J 0
(-1550 4250);
DISPLAY 0.617021 (-1550 4250);
PAINT SKYBLUE (-1550 4250);
FORCEPROP 1 LAST VOLTAGE 4V
J 0
(-1550 4450);
DISPLAY 0.617021 (-1550 4450);
PAINT SKYBLUE (-1550 4450);
FORCEPROP 1 LAST MATERIAL X6S
J 0
(-1550 4350);
DISPLAY 0.617021 (-1550 4350);
PAINT SKYBLUE (-1550 4350);
FORCEPROP 1 LASTPIN (-1600 4550) $PN 1
J 0
(-1590 4530);
DISPLAY 0.617021 (-1590 4530);
PAINT GREEN (-1590 4530);
FORCEPROP 1 LASTPIN (-1600 4350) $PN 2
J 0
(-1590 4330);
DISPLAY 0.617021 (-1590 4330);
PAINT GREEN (-1590 4330);
FORCEPROP 2 LAST CDS_LOCATION C3D5
J 0
(-1550 4550);
DISPLAY 0.617021 (-1550 4550);
PAINT AQUA (-1550 4550);
DISPLAY INVISIBLE (-1550 4550);
FORCEPROP 2 LAST BOM_COST PROC
J 0
(-1600 4450);
PAINT MONO (-1600 4450);
DISPLAY INVISIBLE (-1600 4450);
FORCEPROP 2 LAST CDS_LIB dev_discrete
J 0
(-1600 4450);
PAINT ORANGE (-1600 4450);
DISPLAY INVISIBLE (-1600 4450);
FORCEPROP 2 LAST CDS_SEC 1
J 0
(-1550 4650);
PAINT MONO (-1550 4650);
DISPLAY INVISIBLE (-1550 4650);
FORCEPROP 2 LAST $SEC 1
J 0
(-1550 4650);
PAINT MONO (-1550 4650);
DISPLAY INVISIBLE (-1550 4650);
FORCEPROP 1 LAST PATH I3
J 0
(-1550 4600);
DISPLAY 0.978723 (-1550 4600);
PAINT WHITE (-1550 4600);
DISPLAY INVISIBLE (-1550 4600);
FORCEPROP 2 LAST ROOM PVCCIN_CPU1_DECAP_VR
J 0
(-1550 4550);
PAINT ORANGE (-1550 4550);
DISPLAY INVISIBLE (-1550 4550);
FORCEADD GND..1
(-2100 600);
FORCEPROP 3 LASTPIN (-2100 650) SIG_NAME GND\g
J 0
(-2090 660);
DISPLAY 0.659574 (-2090 660);
PAINT MONO (-2090 660);
DISPLAY INVISIBLE (-2090 660);
FORCEPROP 1 LAST VOLTAGE 0
J 0
(-2100 600);
PAINT SKYBLUE (-2100 600);
DISPLAY INVISIBLE (-2100 600);
FORCEPROP 2 LAST CDS_LIB mstr_symbols
J 0
(-2100 600);
PAINT ORANGE (-2100 600);
DISPLAY INVISIBLE (-2100 600);
FORCEPROP 1 LAST SIZE 1B
J 0
(-2025 550);
DISPLAY 0.893617 (-2025 550);
PAINT GREEN (-2025 550);
DISPLAY INVISIBLE (-2025 550);
FORCEPROP 1 LAST BODY_TYPE PLUMBING
J 0
(-2145 557);
DISPLAY 0.340426 (-2145 557);
PAINT GREEN (-2145 557);
DISPLAY INVISIBLE (-2145 557);
FORCEPROP 1 LAST PATH I30
J 0
(-2025 600);
DISPLAY 0.872340 (-2025 600);
PAINT AQUA (-2025 600);
DISPLAY INVISIBLE (-2025 600);
FORCEPROP 2 LAST ROOM PVCCIN_CPU1_DECAP_VR
J 0
(-2650 675);
PAINT ORANGE (-2650 675);
DISPLAY INVISIBLE (-2650 675);
FORCEPROP 1 LAST HDL_POWER GND
J 0
(-2100 750);
DISPLAY 0.893617 (-2100 750);
PAINT GREEN (-2100 750);
DISPLAY INVISIBLE (-2100 750);
FORCEADD CAP..1
(-2750 3050);
FORCEPROP 1 LAST LOCATION C2D8
J 0
(-2700 3150);
DISPLAY 0.617021 (-2700 3150);
PAINT AQUA (-2700 3150);
FORCEPROP 1 LAST PART_NUMBER E15431-001
J 0
(-2700 2900);
DISPLAY 0.617021 (-2700 2900);
PAINT BLUE (-2700 2900);
FORCEPROP 1 LAST VALUE 10UF
J 0
(-2700 3100);
DISPLAY 0.617021 (-2700 3100);
PAINT SKYBLUE (-2700 3100);
FORCEPROP 1 LAST TOLERANCE 20%
J 0
(-2700 3000);
DISPLAY 0.617021 (-2700 3000);
PAINT SKYBLUE (-2700 3000);
FORCEPROP 1 LAST PACK_TYPE 0603LF
J 0
(-2700 2850);
DISPLAY 0.617021 (-2700 2850);
PAINT SKYBLUE (-2700 2850);
FORCEPROP 1 LAST VOLTAGE 4V
J 0
(-2700 3050);
DISPLAY 0.617021 (-2700 3050);
PAINT SKYBLUE (-2700 3050);
FORCEPROP 1 LAST MATERIAL X6S
J 0
(-2700 2950);
DISPLAY 0.617021 (-2700 2950);
PAINT SKYBLUE (-2700 2950);
FORCEPROP 1 LASTPIN (-2750 2950) $PN 2
J 0
(-2740 2930);
DISPLAY 0.617021 (-2740 2930);
PAINT GREEN (-2740 2930);
FORCEPROP 1 LASTPIN (-2750 3150) $PN 1
J 0
(-2740 3130);
DISPLAY 0.617021 (-2740 3130);
PAINT GREEN (-2740 3130);
FORCEPROP 2 LAST BOM_COST PROC
J 0
(-2750 3050);
PAINT MONO (-2750 3050);
DISPLAY INVISIBLE (-2750 3050);
FORCEPROP 2 LAST CDS_LIB mstr_discrete
J 0
(-2750 3050);
PAINT ORANGE (-2750 3050);
DISPLAY INVISIBLE (-2750 3050);
FORCEPROP 2 LAST CDS_SEC 1
J 0
(-2700 3250);
PAINT MONO (-2700 3250);
DISPLAY INVISIBLE (-2700 3250);
FORCEPROP 2 LAST $SEC 1
J 0
(-2700 3250);
PAINT MONO (-2700 3250);
DISPLAY INVISIBLE (-2700 3250);
FORCEPROP 2 LAST CDS_LOCATION C2D8
J 0
(-2700 3150);
DISPLAY 0.617021 (-2700 3150);
PAINT AQUA (-2700 3150);
DISPLAY INVISIBLE (-2700 3150);
FORCEPROP 1 LAST PATH I33
J 0
(-2700 3200);
DISPLAY 0.978723 (-2700 3200);
PAINT WHITE (-2700 3200);
DISPLAY INVISIBLE (-2700 3200);
FORCEPROP 2 LAST ROOM PVCCIN_CPU1_DECAP_VR
J 0
(-2700 3150);
PAINT ORANGE (-2700 3150);
DISPLAY INVISIBLE (-2700 3150);
FORCEADD GND..1
(-2750 2750);
FORCEPROP 3 LASTPIN (-2750 2800) SIG_NAME GND\g
J 0
(-2740 2810);
DISPLAY 0.659574 (-2740 2810);
PAINT MONO (-2740 2810);
DISPLAY INVISIBLE (-2740 2810);
FORCEPROP 1 LAST VOLTAGE 0
J 0
(-2750 2750);
PAINT SKYBLUE (-2750 2750);
DISPLAY INVISIBLE (-2750 2750);
FORCEPROP 1 LAST SIZE 1B
J 0
(-2675 2700);
DISPLAY 0.893617 (-2675 2700);
PAINT GREEN (-2675 2700);
DISPLAY INVISIBLE (-2675 2700);
FORCEPROP 2 LAST CDS_LIB mstr_symbols
J 0
(-2750 2750);
PAINT ORANGE (-2750 2750);
DISPLAY INVISIBLE (-2750 2750);
FORCEPROP 1 LAST BODY_TYPE PLUMBING
J 0
(-2795 2707);
DISPLAY 0.340426 (-2795 2707);
PAINT GREEN (-2795 2707);
DISPLAY INVISIBLE (-2795 2707);
FORCEPROP 1 LAST PATH I36
J 0
(-2675 2750);
DISPLAY 0.872340 (-2675 2750);
PAINT AQUA (-2675 2750);
DISPLAY INVISIBLE (-2675 2750);
FORCEPROP 2 LAST ROOM PVCCIN_CPU1_DECAP_VR
J 0
(-3300 2825);
PAINT ORANGE (-3300 2825);
DISPLAY INVISIBLE (-3300 2825);
FORCEPROP 1 LAST HDL_POWER GND
J 0
(-2750 2900);
DISPLAY 0.893617 (-2750 2900);
PAINT GREEN (-2750 2900);
DISPLAY INVISIBLE (-2750 2900);
FORCEADD CAP..1
(-3150 3050);
FORCEPROP 1 LAST LOCATION C2D10
J 0
(-3100 3150);
DISPLAY 0.617021 (-3100 3150);
PAINT AQUA (-3100 3150);
FORCEPROP 1 LAST PART_NUMBER E15431-001
J 0
(-3100 2900);
DISPLAY 0.617021 (-3100 2900);
PAINT BLUE (-3100 2900);
FORCEPROP 1 LAST VALUE 10UF
J 0
(-3100 3100);
DISPLAY 0.617021 (-3100 3100);
PAINT SKYBLUE (-3100 3100);
FORCEPROP 1 LAST TOLERANCE 20%
J 0
(-3100 3000);
DISPLAY 0.617021 (-3100 3000);
PAINT SKYBLUE (-3100 3000);
FORCEPROP 1 LAST PACK_TYPE 0603LF
J 0
(-3100 2850);
DISPLAY 0.617021 (-3100 2850);
PAINT SKYBLUE (-3100 2850);
FORCEPROP 1 LAST VOLTAGE 4V
J 0
(-3100 3050);
DISPLAY 0.617021 (-3100 3050);
PAINT SKYBLUE (-3100 3050);
FORCEPROP 1 LAST MATERIAL X6S
J 0
(-3100 2950);
DISPLAY 0.617021 (-3100 2950);
PAINT SKYBLUE (-3100 2950);
FORCEPROP 1 LASTPIN (-3150 2950) $PN 2
J 0
(-3140 2930);
DISPLAY 0.617021 (-3140 2930);
PAINT GREEN (-3140 2930);
FORCEPROP 1 LASTPIN (-3150 3150) $PN 1
J 0
(-3140 3130);
DISPLAY 0.617021 (-3140 3130);
PAINT GREEN (-3140 3130);
FORCEPROP 2 LAST BOM_COST PROC
J 0
(-3150 3050);
PAINT MONO (-3150 3050);
DISPLAY INVISIBLE (-3150 3050);
FORCEPROP 2 LAST CDS_LIB mstr_discrete
J 0
(-3150 3050);
PAINT ORANGE (-3150 3050);
DISPLAY INVISIBLE (-3150 3050);
FORCEPROP 2 LAST CDS_SEC 1
J 0
(-3100 3250);
PAINT MONO (-3100 3250);
DISPLAY INVISIBLE (-3100 3250);
FORCEPROP 2 LAST $SEC 1
J 0
(-3100 3250);
PAINT MONO (-3100 3250);
DISPLAY INVISIBLE (-3100 3250);
FORCEPROP 2 LAST CDS_LOCATION C2D10
J 0
(-3100 3150);
DISPLAY 0.617021 (-3100 3150);
PAINT AQUA (-3100 3150);
DISPLAY INVISIBLE (-3100 3150);
FORCEPROP 1 LAST PATH I37
J 0
(-3100 3200);
DISPLAY 0.978723 (-3100 3200);
PAINT WHITE (-3100 3200);
DISPLAY INVISIBLE (-3100 3200);
FORCEPROP 2 LAST ROOM PVCCIN_CPU1_DECAP_VR
J 0
(-3100 3150);
PAINT ORANGE (-3100 3150);
DISPLAY INVISIBLE (-3100 3150);
FORCEADD CAP_A..1
(-1875 4450);
FORCEPROP 1 LAST LOCATION C3D12
J 0
(-1825 4550);
DISPLAY 0.617021 (-1825 4550);
PAINT AQUA (-1825 4550);
FORCEPROP 1 LAST PART_NUMBER E15431-004
J 0
(-1825 4300);
DISPLAY 0.617021 (-1825 4300);
PAINT BLUE (-1825 4300);
FORCEPROP 1 LAST VALUE 22.0UF
J 0
(-1825 4500);
DISPLAY 0.617021 (-1825 4500);
PAINT SKYBLUE (-1825 4500);
FORCEPROP 1 LAST TOLERANCE 20%
J 0
(-1825 4400);
DISPLAY 0.617021 (-1825 4400);
PAINT SKYBLUE (-1825 4400);
FORCEPROP 1 LAST PACK_TYPE 0603V
J 0
(-1825 4250);
DISPLAY 0.617021 (-1825 4250);
PAINT SKYBLUE (-1825 4250);
FORCEPROP 1 LAST VOLTAGE 4V
J 0
(-1825 4450);
DISPLAY 0.617021 (-1825 4450);
PAINT SKYBLUE (-1825 4450);
FORCEPROP 1 LAST MATERIAL X6S
J 0
(-1825 4350);
DISPLAY 0.617021 (-1825 4350);
PAINT SKYBLUE (-1825 4350);
FORCEPROP 1 LASTPIN (-1875 4550) $PN 1
J 0
(-1865 4530);
DISPLAY 0.617021 (-1865 4530);
PAINT GREEN (-1865 4530);
FORCEPROP 1 LASTPIN (-1875 4350) $PN 2
J 0
(-1865 4330);
DISPLAY 0.617021 (-1865 4330);
PAINT GREEN (-1865 4330);
FORCEPROP 2 LAST CDS_LOCATION C3D12
J 0
(-1825 4550);
DISPLAY 0.617021 (-1825 4550);
PAINT AQUA (-1825 4550);
DISPLAY INVISIBLE (-1825 4550);
FORCEPROP 2 LAST BOM_COST PROC
J 0
(-1875 4450);
PAINT MONO (-1875 4450);
DISPLAY INVISIBLE (-1875 4450);
FORCEPROP 2 LAST CDS_LIB dev_discrete
J 0
(-1875 4450);
PAINT ORANGE (-1875 4450);
DISPLAY INVISIBLE (-1875 4450);
FORCEPROP 2 LAST CDS_SEC 1
J 0
(-1825 4650);
PAINT MONO (-1825 4650);
DISPLAY INVISIBLE (-1825 4650);
FORCEPROP 2 LAST $SEC 1
J 0
(-1825 4650);
PAINT MONO (-1825 4650);
DISPLAY INVISIBLE (-1825 4650);
FORCEPROP 1 LAST PATH I4
J 0
(-1825 4600);
DISPLAY 0.978723 (-1825 4600);
PAINT WHITE (-1825 4600);
DISPLAY INVISIBLE (-1825 4600);
FORCEPROP 2 LAST ROOM PVCCIN_CPU1_DECAP_VR
J 0
(-1825 4550);
PAINT ORANGE (-1825 4550);
DISPLAY INVISIBLE (-1825 4550);
FORCEADD PVSA_CPU1..1
(-3925 3325);
FORCEPROP 3 LASTPIN (-3925 3275) SIG_NAME PVSA_CPU1\g
J 0
(-3915 3285);
DISPLAY 0.659574 (-3915 3285);
PAINT MONO (-3915 3285);
DISPLAY INVISIBLE (-3915 3285);
FORCEPROP 1 LAST VOLTAGE 1.1V
J 0
(-3970 3282);
DISPLAY 0.340426 (-3970 3282);
PAINT SKYBLUE (-3970 3282);
DISPLAY INVISIBLE (-3970 3282);
FORCEPROP 2 LAST CDS_LIB mstr_symbols
J 0
(-3925 3325);
PAINT ORANGE (-3925 3325);
DISPLAY INVISIBLE (-3925 3325);
FORCEPROP 1 LAST BODY_TYPE PLUMBING
J 0
(-3970 3282);
DISPLAY 0.340426 (-3970 3282);
PAINT GREEN (-3970 3282);
DISPLAY INVISIBLE (-3970 3282);
FORCEPROP 1 LAST PATH I41
J 0
(-3875 3350);
DISPLAY 0.872340 (-3875 3350);
PAINT AQUA (-3875 3350);
DISPLAY INVISIBLE (-3875 3350);
FORCEPROP 2 LAST ROOM PVCCIN_CPU1_DECAP_VR
J 0
(-3675 3425);
PAINT ORANGE (-3675 3425);
DISPLAY INVISIBLE (-3675 3425);
FORCEPROP 1 LAST HDL_POWER PVSA_CPU1
J 1
(-3925 3375);
DISPLAY 0.872340 (-3925 3375);
PAINT GREEN (-3925 3375);
DISPLAY INVISIBLE (-3925 3375);
FORCEADD CAP..1
(-3525 3075);
FORCEPROP 1 LAST LOCATION C2D11
J 0
(-3475 3175);
DISPLAY 0.617021 (-3475 3175);
PAINT AQUA (-3475 3175);
FORCEPROP 1 LAST PART_NUMBER E15431-001
J 0
(-3475 2925);
DISPLAY 0.617021 (-3475 2925);
PAINT BLUE (-3475 2925);
FORCEPROP 1 LAST VALUE 10UF
J 0
(-3475 3125);
DISPLAY 0.617021 (-3475 3125);
PAINT SKYBLUE (-3475 3125);
FORCEPROP 1 LAST TOLERANCE 20%
J 0
(-3475 3025);
DISPLAY 0.617021 (-3475 3025);
PAINT SKYBLUE (-3475 3025);
FORCEPROP 1 LAST PACK_TYPE 0603LF
J 0
(-3475 2875);
DISPLAY 0.617021 (-3475 2875);
PAINT SKYBLUE (-3475 2875);
FORCEPROP 1 LAST VOLTAGE 4V
J 0
(-3475 3075);
DISPLAY 0.617021 (-3475 3075);
PAINT SKYBLUE (-3475 3075);
FORCEPROP 1 LAST MATERIAL X6S
J 0
(-3475 2975);
DISPLAY 0.617021 (-3475 2975);
PAINT SKYBLUE (-3475 2975);
FORCEPROP 1 LASTPIN (-3525 2975) $PN 2
J 0
(-3515 2955);
DISPLAY 0.617021 (-3515 2955);
PAINT GREEN (-3515 2955);
FORCEPROP 1 LASTPIN (-3525 3175) $PN 1
J 0
(-3515 3155);
DISPLAY 0.617021 (-3515 3155);
PAINT GREEN (-3515 3155);
FORCEPROP 2 LAST CDS_LIB mstr_discrete
J 0
(-3525 3075);
PAINT ORANGE (-3525 3075);
DISPLAY INVISIBLE (-3525 3075);
FORCEPROP 2 LAST BOM_COST PROC
J 0
(-3525 3075);
PAINT MONO (-3525 3075);
DISPLAY INVISIBLE (-3525 3075);
FORCEPROP 2 LAST CDS_SEC 1
J 0
(-3475 3275);
PAINT MONO (-3475 3275);
DISPLAY INVISIBLE (-3475 3275);
FORCEPROP 2 LAST $SEC 1
J 0
(-3475 3275);
PAINT MONO (-3475 3275);
DISPLAY INVISIBLE (-3475 3275);
FORCEPROP 2 LAST CDS_LOCATION C2D11
J 0
(-3475 3175);
DISPLAY 0.617021 (-3475 3175);
PAINT AQUA (-3475 3175);
DISPLAY INVISIBLE (-3475 3175);
FORCEPROP 1 LAST PATH I42
J 0
(-3475 3225);
DISPLAY 0.978723 (-3475 3225);
PAINT WHITE (-3475 3225);
DISPLAY INVISIBLE (-3475 3225);
FORCEPROP 2 LAST ROOM PVCCIN_CPU1_DECAP_VR
J 0
(-3475 3175);
PAINT ORANGE (-3475 3175);
DISPLAY INVISIBLE (-3475 3175);
FORCEADD CAP..1
(-3925 3050);
FORCEPROP 1 LAST LOCATION C2D9
J 0
(-3875 3150);
DISPLAY 0.617021 (-3875 3150);
PAINT AQUA (-3875 3150);
FORCEPROP 1 LAST PART_NUMBER E15431-001
J 0
(-3875 2900);
DISPLAY 0.617021 (-3875 2900);
PAINT BLUE (-3875 2900);
FORCEPROP 1 LAST VALUE 10UF
J 0
(-3875 3100);
DISPLAY 0.617021 (-3875 3100);
PAINT SKYBLUE (-3875 3100);
FORCEPROP 1 LAST TOLERANCE 20%
J 0
(-3875 3000);
DISPLAY 0.617021 (-3875 3000);
PAINT SKYBLUE (-3875 3000);
FORCEPROP 1 LAST PACK_TYPE 0603LF
J 0
(-3875 2850);
DISPLAY 0.617021 (-3875 2850);
PAINT SKYBLUE (-3875 2850);
FORCEPROP 1 LAST VOLTAGE 4V
J 0
(-3875 3050);
DISPLAY 0.617021 (-3875 3050);
PAINT SKYBLUE (-3875 3050);
FORCEPROP 1 LAST MATERIAL X6S
J 0
(-3875 2950);
DISPLAY 0.617021 (-3875 2950);
PAINT SKYBLUE (-3875 2950);
FORCEPROP 1 LASTPIN (-3925 2950) $PN 2
J 0
(-3915 2930);
DISPLAY 0.617021 (-3915 2930);
PAINT GREEN (-3915 2930);
FORCEPROP 1 LASTPIN (-3925 3150) $PN 1
J 0
(-3915 3130);
DISPLAY 0.617021 (-3915 3130);
PAINT GREEN (-3915 3130);
FORCEPROP 2 LAST CDS_LIB mstr_discrete
J 0
(-3925 3050);
PAINT ORANGE (-3925 3050);
DISPLAY INVISIBLE (-3925 3050);
FORCEPROP 2 LAST BOM_COST PROC
J 0
(-3925 3050);
PAINT MONO (-3925 3050);
DISPLAY INVISIBLE (-3925 3050);
FORCEPROP 2 LAST CDS_SEC 1
J 0
(-3875 3250);
PAINT MONO (-3875 3250);
DISPLAY INVISIBLE (-3875 3250);
FORCEPROP 2 LAST $SEC 1
J 0
(-3875 3250);
PAINT MONO (-3875 3250);
DISPLAY INVISIBLE (-3875 3250);
FORCEPROP 2 LAST CDS_LOCATION C2D9
J 0
(-3875 3150);
DISPLAY 0.617021 (-3875 3150);
PAINT AQUA (-3875 3150);
DISPLAY INVISIBLE (-3875 3150);
FORCEPROP 1 LAST PATH I43
J 0
(-3875 3200);
DISPLAY 0.978723 (-3875 3200);
PAINT WHITE (-3875 3200);
DISPLAY INVISIBLE (-3875 3200);
FORCEPROP 2 LAST ROOM PVCCIN_CPU1_DECAP_VR
J 0
(-3875 3150);
PAINT ORANGE (-3875 3150);
DISPLAY INVISIBLE (-3875 3150);
FORCEADD CAP..1
(-3725 2150);
FORCEPROP 1 LAST LOCATION C7P15
J 0
(-3675 2250);
DISPLAY 0.617021 (-3675 2250);
PAINT AQUA (-3675 2250);
FORCEPROP 1 LAST PART_NUMBER C95333-006
R 1
J 0
(-3775 1975);
DISPLAY 0.617021 (-3775 1975);
PAINT BLUE (-3775 1975);
FORCEPROP 1 LAST VALUE 47UF
J 0
(-3675 2200);
DISPLAY 0.617021 (-3675 2200);
PAINT SKYBLUE (-3675 2200);
FORCEPROP 1 LAST TOLERANCE 20%
J 0
(-3675 2100);
DISPLAY 0.617021 (-3675 2100);
PAINT SKYBLUE (-3675 2100);
FORCEPROP 1 LAST PACK_TYPE 0805
J 0
(-3675 2000);
DISPLAY 0.617021 (-3675 2000);
PAINT SKYBLUE (-3675 2000);
FORCEPROP 1 LASTPIN (-3725 2050) $PN 2
J 0
(-3715 2030);
DISPLAY 0.617021 (-3715 2030);
PAINT GREEN (-3715 2030);
FORCEPROP 1 LASTPIN (-3725 2250) $PN 1
J 0
(-3715 2230);
DISPLAY 0.617021 (-3715 2230);
PAINT GREEN (-3715 2230);
FORCEPROP 1 LAST VOLTAGE 4V
J 0
(-3675 2150);
PAINT SKYBLUE (-3675 2150);
DISPLAY INVISIBLE (-3675 2150);
FORCEPROP 1 LAST MATERIAL X6S
J 0
(-3675 2050);
PAINT SKYBLUE (-3675 2050);
DISPLAY INVISIBLE (-3675 2050);
FORCEPROP 2 LAST BOM_COST PROC
J 0
(-3725 2150);
PAINT MONO (-3725 2150);
DISPLAY INVISIBLE (-3725 2150);
FORCEPROP 2 LAST CDS_LIB mstr_discrete
J 0
(-3725 2150);
PAINT ORANGE (-3725 2150);
DISPLAY INVISIBLE (-3725 2150);
FORCEPROP 2 LAST CDS_SEC 1
J 0
(-3675 2350);
DISPLAY 1.021277 (-3675 2350);
PAINT ORANGE (-3675 2350);
DISPLAY INVISIBLE (-3675 2350);
FORCEPROP 2 LAST $SEC 1
J 0
(-3675 2350);
DISPLAY 0.680851 (-3675 2350);
PAINT MONO (-3675 2350);
DISPLAY INVISIBLE (-3675 2350);
FORCEPROP 2 LAST CDS_LOCATION C7P15
J 0
(-3675 2250);
DISPLAY 0.617021 (-3675 2250);
PAINT AQUA (-3675 2250);
DISPLAY INVISIBLE (-3675 2250);
FORCEPROP 1 LAST PATH I45
J 0
(-3675 2300);
DISPLAY 0.978723 (-3675 2300);
PAINT WHITE (-3675 2300);
DISPLAY INVISIBLE (-3675 2300);
FORCEPROP 2 LAST ROOM PVCCIN_CPU1_DECAP_VR
J 0
(-3675 2250);
PAINT ORANGE (-3675 2250);
DISPLAY INVISIBLE (-3675 2250);
FORCEADD PVCCIO_CPU1..1
(-3300 1200);
FORCEPROP 3 LASTPIN (-3300 1150) SIG_NAME PVCCIO_CPU1\g
J 0
(-3290 1160);
DISPLAY 0.659574 (-3290 1160);
PAINT MONO (-3290 1160);
DISPLAY INVISIBLE (-3290 1160);
FORCEPROP 1 LAST VOLTAGE 1.1V
J 0
(-3345 1157);
DISPLAY 0.340426 (-3345 1157);
PAINT SKYBLUE (-3345 1157);
DISPLAY INVISIBLE (-3345 1157);
FORCEPROP 2 LAST CDS_LIB mstr_symbols
J 0
(-3300 1200);
PAINT ORANGE (-3300 1200);
DISPLAY INVISIBLE (-3300 1200);
FORCEPROP 1 LAST BODY_TYPE PLUMBING
J 0
(-3345 1157);
DISPLAY 0.340426 (-3345 1157);
PAINT GREEN (-3345 1157);
DISPLAY INVISIBLE (-3345 1157);
FORCEPROP 1 LAST PATH I47
J 0
(-3250 1225);
DISPLAY 0.872340 (-3250 1225);
PAINT AQUA (-3250 1225);
DISPLAY INVISIBLE (-3250 1225);
FORCEPROP 1 LAST HDL_POWER PVCCIO_CPU1
J 1
(-3300 1250);
DISPLAY 0.872340 (-3300 1250);
PAINT GREEN (-3300 1250);
DISPLAY INVISIBLE (-3300 1250);
FORCEADD CAP..1
(-4000 2150);
FORCEPROP 1 LAST LOCATION C8P23
J 0
(-3950 2250);
DISPLAY 0.617021 (-3950 2250);
PAINT AQUA (-3950 2250);
FORCEPROP 1 LAST PART_NUMBER C95333-006
R 1
J 0
(-4050 1975);
DISPLAY 0.617021 (-4050 1975);
PAINT BLUE (-4050 1975);
FORCEPROP 1 LAST VALUE 47UF
J 0
(-3950 2200);
DISPLAY 0.617021 (-3950 2200);
PAINT SKYBLUE (-3950 2200);
FORCEPROP 1 LAST TOLERANCE 20%
J 0
(-3950 2100);
DISPLAY 0.617021 (-3950 2100);
PAINT SKYBLUE (-3950 2100);
FORCEPROP 1 LAST PACK_TYPE 0805
J 0
(-3950 2000);
DISPLAY 0.617021 (-3950 2000);
PAINT SKYBLUE (-3950 2000);
FORCEPROP 1 LASTPIN (-4000 2050) $PN 2
J 0
(-3990 2030);
DISPLAY 0.617021 (-3990 2030);
PAINT GREEN (-3990 2030);
FORCEPROP 1 LASTPIN (-4000 2250) $PN 1
J 0
(-3990 2230);
DISPLAY 0.617021 (-3990 2230);
PAINT GREEN (-3990 2230);
FORCEPROP 1 LAST VOLTAGE 4V
J 0
(-3950 2150);
PAINT SKYBLUE (-3950 2150);
DISPLAY INVISIBLE (-3950 2150);
FORCEPROP 1 LAST MATERIAL X6S
J 0
(-3950 2050);
PAINT SKYBLUE (-3950 2050);
DISPLAY INVISIBLE (-3950 2050);
FORCEPROP 2 LAST CDS_LIB mstr_discrete
J 0
(-4000 2150);
PAINT ORANGE (-4000 2150);
DISPLAY INVISIBLE (-4000 2150);
FORCEPROP 2 LAST BOM_COST PROC
J 0
(-4000 2150);
PAINT MONO (-4000 2150);
DISPLAY INVISIBLE (-4000 2150);
FORCEPROP 2 LAST CDS_SEC 1
J 0
(-3950 2350);
DISPLAY 1.021277 (-3950 2350);
PAINT ORANGE (-3950 2350);
DISPLAY INVISIBLE (-3950 2350);
FORCEPROP 2 LAST $SEC 1
J 0
(-3950 2350);
DISPLAY 0.680851 (-3950 2350);
PAINT MONO (-3950 2350);
DISPLAY INVISIBLE (-3950 2350);
FORCEPROP 2 LAST CDS_LOCATION C8P23
J 0
(-3950 2250);
DISPLAY 0.617021 (-3950 2250);
PAINT AQUA (-3950 2250);
DISPLAY INVISIBLE (-3950 2250);
FORCEPROP 1 LAST PATH I48
J 0
(-3950 2300);
DISPLAY 0.978723 (-3950 2300);
PAINT WHITE (-3950 2300);
DISPLAY INVISIBLE (-3950 2300);
FORCEPROP 2 LAST ROOM PVCCIN_CPU1_DECAP_VR
J 0
(-3950 2250);
PAINT ORANGE (-3950 2250);
DISPLAY INVISIBLE (-3950 2250);
FORCEADD CAP..1
(-4275 2125);
FORCEPROP 1 LAST LOCATION C7P14
J 0
(-4225 2225);
DISPLAY 0.617021 (-4225 2225);
PAINT AQUA (-4225 2225);
FORCEPROP 1 LAST PART_NUMBER C95333-006
R 1
J 0
(-4325 1950);
DISPLAY 0.617021 (-4325 1950);
PAINT BLUE (-4325 1950);
FORCEPROP 1 LAST VALUE 47UF
J 0
(-4225 2175);
DISPLAY 0.617021 (-4225 2175);
PAINT SKYBLUE (-4225 2175);
FORCEPROP 1 LAST TOLERANCE 20%
J 0
(-4225 2075);
DISPLAY 0.617021 (-4225 2075);
PAINT SKYBLUE (-4225 2075);
FORCEPROP 1 LAST PACK_TYPE 0805
J 0
(-4225 1975);
DISPLAY 0.617021 (-4225 1975);
PAINT SKYBLUE (-4225 1975);
FORCEPROP 1 LASTPIN (-4275 2025) $PN 2
J 0
(-4265 2005);
DISPLAY 0.617021 (-4265 2005);
PAINT GREEN (-4265 2005);
FORCEPROP 1 LASTPIN (-4275 2225) $PN 1
J 0
(-4265 2205);
DISPLAY 0.617021 (-4265 2205);
PAINT GREEN (-4265 2205);
FORCEPROP 1 LAST VOLTAGE 4V
J 0
(-4225 2125);
PAINT SKYBLUE (-4225 2125);
DISPLAY INVISIBLE (-4225 2125);
FORCEPROP 1 LAST MATERIAL X6S
J 0
(-4225 2025);
PAINT SKYBLUE (-4225 2025);
DISPLAY INVISIBLE (-4225 2025);
FORCEPROP 2 LAST BOM_COST PROC
J 0
(-4275 2125);
PAINT MONO (-4275 2125);
DISPLAY INVISIBLE (-4275 2125);
FORCEPROP 2 LAST CDS_LIB mstr_discrete
J 0
(-4275 2125);
PAINT ORANGE (-4275 2125);
DISPLAY INVISIBLE (-4275 2125);
FORCEPROP 2 LAST CDS_SEC 1
J 0
(-4225 2325);
DISPLAY 1.021277 (-4225 2325);
PAINT ORANGE (-4225 2325);
DISPLAY INVISIBLE (-4225 2325);
FORCEPROP 2 LAST $SEC 1
J 0
(-4225 2325);
DISPLAY 0.680851 (-4225 2325);
PAINT MONO (-4225 2325);
DISPLAY INVISIBLE (-4225 2325);
FORCEPROP 2 LAST CDS_LOCATION C7P14
J 0
(-4225 2225);
DISPLAY 0.617021 (-4225 2225);
PAINT AQUA (-4225 2225);
DISPLAY INVISIBLE (-4225 2225);
FORCEPROP 1 LAST PATH I49
J 0
(-4225 2275);
DISPLAY 0.978723 (-4225 2275);
PAINT WHITE (-4225 2275);
DISPLAY INVISIBLE (-4225 2275);
FORCEPROP 2 LAST ROOM PVCCIN_CPU1_DECAP_VR
J 0
(-4225 2225);
PAINT ORANGE (-4225 2225);
DISPLAY INVISIBLE (-4225 2225);
FORCEADD CAP_A..1
(-2175 4450);
FORCEPROP 1 LAST LOCATION C3D4
J 0
(-2125 4550);
DISPLAY 0.617021 (-2125 4550);
PAINT AQUA (-2125 4550);
FORCEPROP 1 LAST PART_NUMBER E15431-004
J 0
(-2125 4300);
DISPLAY 0.617021 (-2125 4300);
PAINT BLUE (-2125 4300);
FORCEPROP 1 LAST VALUE 22.0UF
J 0
(-2125 4500);
DISPLAY 0.617021 (-2125 4500);
PAINT SKYBLUE (-2125 4500);
FORCEPROP 1 LAST TOLERANCE 20%
J 0
(-2125 4400);
DISPLAY 0.617021 (-2125 4400);
PAINT SKYBLUE (-2125 4400);
FORCEPROP 1 LAST PACK_TYPE 0603V
J 0
(-2125 4250);
DISPLAY 0.617021 (-2125 4250);
PAINT SKYBLUE (-2125 4250);
FORCEPROP 1 LAST VOLTAGE 4V
J 0
(-2125 4450);
DISPLAY 0.617021 (-2125 4450);
PAINT SKYBLUE (-2125 4450);
FORCEPROP 1 LAST MATERIAL X6S
J 0
(-2125 4350);
DISPLAY 0.617021 (-2125 4350);
PAINT SKYBLUE (-2125 4350);
FORCEPROP 1 LASTPIN (-2175 4550) $PN 1
J 0
(-2165 4530);
DISPLAY 0.617021 (-2165 4530);
PAINT GREEN (-2165 4530);
FORCEPROP 1 LASTPIN (-2175 4350) $PN 2
J 0
(-2165 4330);
DISPLAY 0.617021 (-2165 4330);
PAINT GREEN (-2165 4330);
FORCEPROP 2 LAST CDS_LOCATION C3D4
J 0
(-2125 4550);
DISPLAY 0.617021 (-2125 4550);
PAINT AQUA (-2125 4550);
DISPLAY INVISIBLE (-2125 4550);
FORCEPROP 2 LAST BOM_COST PROC
J 0
(-2175 4450);
PAINT MONO (-2175 4450);
DISPLAY INVISIBLE (-2175 4450);
FORCEPROP 2 LAST CDS_LIB dev_discrete
J 0
(-2175 4450);
PAINT ORANGE (-2175 4450);
DISPLAY INVISIBLE (-2175 4450);
FORCEPROP 2 LAST CDS_SEC 1
J 0
(-2125 4650);
PAINT MONO (-2125 4650);
DISPLAY INVISIBLE (-2125 4650);
FORCEPROP 2 LAST $SEC 1
J 0
(-2125 4650);
PAINT MONO (-2125 4650);
DISPLAY INVISIBLE (-2125 4650);
FORCEPROP 1 LAST PATH I5
J 0
(-2125 4600);
DISPLAY 0.978723 (-2125 4600);
PAINT WHITE (-2125 4600);
DISPLAY INVISIBLE (-2125 4600);
FORCEPROP 2 LAST ROOM PVCCIN_CPU1_DECAP_VR
J 0
(-2125 4550);
PAINT ORANGE (-2125 4550);
DISPLAY INVISIBLE (-2125 4550);
FORCEADD CAP..1
(-3800 950);
FORCEPROP 1 LAST LOCATION C8P7
J 0
(-3750 1050);
DISPLAY 0.617021 (-3750 1050);
PAINT AQUA (-3750 1050);
FORCEPROP 1 LAST PART_NUMBER C95333-002
R 1
J 0
(-3850 775);
DISPLAY 0.617021 (-3850 775);
PAINT BLUE (-3850 775);
FORCEPROP 1 LAST VALUE 22UF
J 0
(-3750 1000);
DISPLAY 0.617021 (-3750 1000);
PAINT SKYBLUE (-3750 1000);
FORCEPROP 1 LAST TOLERANCE 20%
J 0
(-3750 900);
DISPLAY 0.617021 (-3750 900);
PAINT SKYBLUE (-3750 900);
FORCEPROP 1 LAST PACK_TYPE 0805LF
J 0
(-3750 800);
DISPLAY 0.617021 (-3750 800);
PAINT SKYBLUE (-3750 800);
FORCEPROP 1 LASTPIN (-3800 850) $PN 2
J 0
(-3790 830);
DISPLAY 0.617021 (-3790 830);
PAINT GREEN (-3790 830);
FORCEPROP 1 LASTPIN (-3800 1050) $PN 1
J 0
(-3790 1030);
DISPLAY 0.617021 (-3790 1030);
PAINT GREEN (-3790 1030);
FORCEPROP 1 LAST VOLTAGE 4V
J 0
(-3750 950);
PAINT SKYBLUE (-3750 950);
DISPLAY INVISIBLE (-3750 950);
FORCEPROP 1 LAST MATERIAL X6S
J 0
(-3750 850);
PAINT SKYBLUE (-3750 850);
DISPLAY INVISIBLE (-3750 850);
FORCEPROP 2 LAST CDS_LIB mstr_discrete
J 0
(-3800 950);
PAINT ORANGE (-3800 950);
DISPLAY INVISIBLE (-3800 950);
FORCEPROP 2 LAST BOM_COST PROC
J 0
(-3800 950);
PAINT MONO (-3800 950);
DISPLAY INVISIBLE (-3800 950);
FORCEPROP 2 LAST CDS_SEC 1
J 0
(-3750 1150);
DISPLAY 1.021277 (-3750 1150);
PAINT ORANGE (-3750 1150);
DISPLAY INVISIBLE (-3750 1150);
FORCEPROP 2 LAST $SEC 1
J 0
(-3750 1150);
DISPLAY 0.680851 (-3750 1150);
PAINT MONO (-3750 1150);
DISPLAY INVISIBLE (-3750 1150);
FORCEPROP 2 LAST CDS_LOCATION C8P7
J 0
(-3750 1050);
DISPLAY 0.617021 (-3750 1050);
PAINT AQUA (-3750 1050);
DISPLAY INVISIBLE (-3750 1050);
FORCEPROP 1 LAST PATH I50
J 0
(-3750 1100);
DISPLAY 0.978723 (-3750 1100);
PAINT WHITE (-3750 1100);
DISPLAY INVISIBLE (-3750 1100);
FORCEPROP 2 LAST ROOM PVCCIN_CPU1_DECAP_VR
J 0
(-3750 1050);
PAINT ORANGE (-3750 1050);
DISPLAY INVISIBLE (-3750 1050);
FORCEADD CAP..1
(-2950 925);
FORCEPROP 1 LAST LOCATION C7P18
J 0
(-2900 1025);
DISPLAY 0.617021 (-2900 1025);
PAINT AQUA (-2900 1025);
FORCEPROP 1 LAST PART_NUMBER C95333-006
J 0
(-2900 825);
DISPLAY 0.617021 (-2900 825);
PAINT BLUE (-2900 825);
FORCEPROP 1 LAST VALUE 47UF
J 0
(-2900 975);
DISPLAY 0.617021 (-2900 975);
PAINT SKYBLUE (-2900 975);
FORCEPROP 1 LAST TOLERANCE 20%
J 0
(-2900 875);
DISPLAY 0.617021 (-2900 875);
PAINT SKYBLUE (-2900 875);
FORCEPROP 1 LAST PACK_TYPE 0805
J 0
(-2900 775);
DISPLAY 0.617021 (-2900 775);
PAINT SKYBLUE (-2900 775);
FORCEPROP 1 LASTPIN (-2950 825) $PN 2
J 0
(-2940 805);
DISPLAY 0.617021 (-2940 805);
PAINT ORANGE (-2940 805);
FORCEPROP 1 LASTPIN (-2950 1025) $PN 1
J 0
(-2940 1005);
DISPLAY 0.617021 (-2940 1005);
PAINT ORANGE (-2940 1005);
FORCEPROP 1 LAST VOLTAGE 4V
J 0
(-2900 925);
PAINT SKYBLUE (-2900 925);
DISPLAY INVISIBLE (-2900 925);
FORCEPROP 1 LAST MATERIAL X6S
J 0
(-2900 825);
PAINT SKYBLUE (-2900 825);
DISPLAY INVISIBLE (-2900 825);
FORCEPROP 2 LAST BOM_COST PROC
J 0
(-2950 925);
PAINT MONO (-2950 925);
DISPLAY INVISIBLE (-2950 925);
FORCEPROP 2 LAST CDS_LIB mstr_discrete
J 0
(-2950 925);
PAINT ORANGE (-2950 925);
DISPLAY INVISIBLE (-2950 925);
FORCEPROP 2 LAST CDS_SEC 1
J 0
(-2890 1145);
PAINT MONO (-2890 1145);
DISPLAY INVISIBLE (-2890 1145);
FORCEPROP 2 LAST $SEC 1
J 0
(-2890 1145);
PAINT MONO (-2890 1145);
DISPLAY INVISIBLE (-2890 1145);
FORCEPROP 2 LAST CDS_LOCATION C7P18
J 0
(-2900 1025);
DISPLAY 0.617021 (-2900 1025);
PAINT AQUA (-2900 1025);
DISPLAY INVISIBLE (-2900 1025);
FORCEPROP 1 LAST PATH I51
J 0
(-2900 1075);
DISPLAY 0.978723 (-2900 1075);
PAINT WHITE (-2900 1075);
DISPLAY INVISIBLE (-2900 1075);
FORCEPROP 2 LAST ROOM PVCCIN_CPU1_DECAP_VR
J 0
(-2875 1025);
PAINT ORANGE (-2875 1025);
DISPLAY INVISIBLE (-2875 1025);
FORCEADD CAP..1
(-3300 925);
FORCEPROP 1 LAST LOCATION C7P3
J 0
(-3250 1025);
DISPLAY 0.617021 (-3250 1025);
PAINT AQUA (-3250 1025);
FORCEPROP 1 LAST PART_NUMBER C95333-006
J 0
(-3250 825);
DISPLAY 0.617021 (-3250 825);
PAINT BLUE (-3250 825);
FORCEPROP 1 LAST VALUE 47UF
J 0
(-3250 975);
DISPLAY 0.617021 (-3250 975);
PAINT SKYBLUE (-3250 975);
FORCEPROP 1 LAST TOLERANCE 20%
J 0
(-3250 875);
DISPLAY 0.617021 (-3250 875);
PAINT SKYBLUE (-3250 875);
FORCEPROP 1 LAST PACK_TYPE 0805
J 0
(-3250 775);
DISPLAY 0.617021 (-3250 775);
PAINT SKYBLUE (-3250 775);
FORCEPROP 1 LASTPIN (-3300 825) $PN 2
J 0
(-3290 805);
DISPLAY 0.617021 (-3290 805);
PAINT ORANGE (-3290 805);
FORCEPROP 1 LASTPIN (-3300 1025) $PN 1
J 0
(-3290 1005);
DISPLAY 0.617021 (-3290 1005);
PAINT ORANGE (-3290 1005);
FORCEPROP 1 LAST VOLTAGE 4V
J 0
(-3250 925);
PAINT SKYBLUE (-3250 925);
DISPLAY INVISIBLE (-3250 925);
FORCEPROP 1 LAST MATERIAL X6S
J 0
(-3250 825);
PAINT SKYBLUE (-3250 825);
DISPLAY INVISIBLE (-3250 825);
FORCEPROP 2 LAST BOM_COST PROC
J 0
(-3300 925);
PAINT MONO (-3300 925);
DISPLAY INVISIBLE (-3300 925);
FORCEPROP 2 LAST CDS_LIB mstr_discrete
J 0
(-3300 925);
PAINT ORANGE (-3300 925);
DISPLAY INVISIBLE (-3300 925);
FORCEPROP 2 LAST CDS_SEC 1
J 0
(-3240 1145);
PAINT MONO (-3240 1145);
DISPLAY INVISIBLE (-3240 1145);
FORCEPROP 2 LAST $SEC 1
J 0
(-3240 1145);
PAINT MONO (-3240 1145);
DISPLAY INVISIBLE (-3240 1145);
FORCEPROP 2 LAST CDS_LOCATION C7P3
J 0
(-3250 1025);
DISPLAY 0.617021 (-3250 1025);
PAINT AQUA (-3250 1025);
DISPLAY INVISIBLE (-3250 1025);
FORCEPROP 1 LAST PATH I52
J 0
(-3250 1075);
DISPLAY 0.978723 (-3250 1075);
PAINT WHITE (-3250 1075);
DISPLAY INVISIBLE (-3250 1075);
FORCEPROP 2 LAST ROOM PVCCIN_CPU1_DECAP_VR
J 0
(-3250 1025);
PAINT ORANGE (-3250 1025);
DISPLAY INVISIBLE (-3250 1025);
FORCEADD GND..1
(-3800 625);
FORCEPROP 3 LASTPIN (-3800 675) SIG_NAME GND\g
J 0
(-3790 685);
DISPLAY 0.659574 (-3790 685);
PAINT MONO (-3790 685);
DISPLAY INVISIBLE (-3790 685);
FORCEPROP 1 LAST VOLTAGE 0
J 0
(-3800 625);
PAINT SKYBLUE (-3800 625);
DISPLAY INVISIBLE (-3800 625);
FORCEPROP 2 LAST CDS_LIB mstr_symbols
J 0
(-3800 625);
PAINT MONO (-3800 625);
DISPLAY INVISIBLE (-3800 625);
FORCEPROP 1 LAST SIZE 1B
J 0
(-3725 575);
DISPLAY 0.893617 (-3725 575);
PAINT GREEN (-3725 575);
DISPLAY INVISIBLE (-3725 575);
FORCEPROP 1 LAST BODY_TYPE PLUMBING
J 0
(-3845 582);
DISPLAY 0.340426 (-3845 582);
PAINT GREEN (-3845 582);
DISPLAY INVISIBLE (-3845 582);
FORCEPROP 1 LAST PATH I53
J 0
(-3725 625);
DISPLAY 0.872340 (-3725 625);
PAINT AQUA (-3725 625);
DISPLAY INVISIBLE (-3725 625);
FORCEPROP 2 LAST ROOM PVCCIN_CPU1_DECAP_VR
J 0
(-4350 700);
PAINT ORANGE (-4350 700);
DISPLAY INVISIBLE (-4350 700);
FORCEPROP 1 LAST HDL_POWER GND
J 0
(-3800 775);
DISPLAY 0.893617 (-3800 775);
PAINT GREEN (-3800 775);
DISPLAY INVISIBLE (-3800 775);
FORCEADD CAP..1
(-4125 950);
FORCEPROP 1 LAST LOCATION C8P6
J 0
(-4075 1050);
DISPLAY 0.617021 (-4075 1050);
PAINT AQUA (-4075 1050);
FORCEPROP 1 LAST PART_NUMBER C95333-002
R 1
J 0
(-4175 775);
DISPLAY 0.617021 (-4175 775);
PAINT BLUE (-4175 775);
FORCEPROP 1 LAST VALUE 22UF
J 0
(-4075 1000);
DISPLAY 0.617021 (-4075 1000);
PAINT SKYBLUE (-4075 1000);
FORCEPROP 1 LAST TOLERANCE 20%
J 0
(-4075 900);
DISPLAY 0.617021 (-4075 900);
PAINT SKYBLUE (-4075 900);
FORCEPROP 1 LAST PACK_TYPE 0805LF
J 0
(-4075 800);
DISPLAY 0.617021 (-4075 800);
PAINT SKYBLUE (-4075 800);
FORCEPROP 1 LASTPIN (-4125 850) $PN 2
J 0
(-4115 830);
DISPLAY 0.617021 (-4115 830);
PAINT GREEN (-4115 830);
FORCEPROP 1 LASTPIN (-4125 1050) $PN 1
J 0
(-4115 1030);
DISPLAY 0.617021 (-4115 1030);
PAINT GREEN (-4115 1030);
FORCEPROP 1 LAST VOLTAGE 4V
J 0
(-4075 950);
PAINT SKYBLUE (-4075 950);
DISPLAY INVISIBLE (-4075 950);
FORCEPROP 1 LAST MATERIAL X6S
J 0
(-4075 850);
PAINT SKYBLUE (-4075 850);
DISPLAY INVISIBLE (-4075 850);
FORCEPROP 2 LAST CDS_LIB mstr_discrete
J 0
(-4125 950);
PAINT ORANGE (-4125 950);
DISPLAY INVISIBLE (-4125 950);
FORCEPROP 2 LAST BOM_COST PROC
J 0
(-4125 950);
PAINT MONO (-4125 950);
DISPLAY INVISIBLE (-4125 950);
FORCEPROP 2 LAST CDS_SEC 1
J 0
(-4075 1150);
DISPLAY 1.021277 (-4075 1150);
PAINT ORANGE (-4075 1150);
DISPLAY INVISIBLE (-4075 1150);
FORCEPROP 2 LAST $SEC 1
J 0
(-4075 1150);
DISPLAY 0.680851 (-4075 1150);
PAINT MONO (-4075 1150);
DISPLAY INVISIBLE (-4075 1150);
FORCEPROP 2 LAST CDS_LOCATION C8P6
J 0
(-4075 1050);
DISPLAY 0.617021 (-4075 1050);
PAINT AQUA (-4075 1050);
DISPLAY INVISIBLE (-4075 1050);
FORCEPROP 1 LAST PATH I55
J 0
(-4075 1100);
DISPLAY 0.978723 (-4075 1100);
PAINT WHITE (-4075 1100);
DISPLAY INVISIBLE (-4075 1100);
FORCEPROP 2 LAST ROOM PVCCIN_CPU1_DECAP_VR
J 0
(-4050 1050);
PAINT ORANGE (-4050 1050);
DISPLAY INVISIBLE (-4050 1050);
FORCEADD PVSA_CPU1..1
(-4475 1225);
FORCEPROP 3 LASTPIN (-4475 1175) SIG_NAME PVSA_CPU1\g
J 0
(-4465 1185);
DISPLAY 0.659574 (-4465 1185);
PAINT MONO (-4465 1185);
DISPLAY INVISIBLE (-4465 1185);
FORCEPROP 1 LAST VOLTAGE 1.1V
J 0
(-4520 1182);
DISPLAY 0.340426 (-4520 1182);
PAINT SKYBLUE (-4520 1182);
DISPLAY INVISIBLE (-4520 1182);
FORCEPROP 2 LAST CDS_LIB mstr_symbols
J 0
(-4475 1225);
PAINT ORANGE (-4475 1225);
DISPLAY INVISIBLE (-4475 1225);
FORCEPROP 1 LAST BODY_TYPE PLUMBING
J 0
(-4520 1182);
DISPLAY 0.340426 (-4520 1182);
PAINT GREEN (-4520 1182);
DISPLAY INVISIBLE (-4520 1182);
FORCEPROP 1 LAST PATH I57
J 0
(-4425 1250);
DISPLAY 0.872340 (-4425 1250);
PAINT AQUA (-4425 1250);
DISPLAY INVISIBLE (-4425 1250);
FORCEPROP 1 LAST HDL_POWER PVSA_CPU1
J 1
(-4475 1275);
DISPLAY 0.872340 (-4475 1275);
PAINT GREEN (-4475 1275);
DISPLAY INVISIBLE (-4475 1275);
FORCEADD CAP..1
(-4475 950);
FORCEPROP 1 LAST LOCATION C8P5
J 0
(-4425 1050);
DISPLAY 0.617021 (-4425 1050);
PAINT AQUA (-4425 1050);
FORCEPROP 1 LAST PART_NUMBER C95333-002
R 1
J 0
(-4525 775);
DISPLAY 0.617021 (-4525 775);
PAINT BLUE (-4525 775);
FORCEPROP 1 LAST VALUE 22UF
J 0
(-4425 1000);
DISPLAY 0.617021 (-4425 1000);
PAINT SKYBLUE (-4425 1000);
FORCEPROP 1 LAST TOLERANCE 20%
J 0
(-4425 900);
DISPLAY 0.617021 (-4425 900);
PAINT SKYBLUE (-4425 900);
FORCEPROP 1 LAST PACK_TYPE 0805LF
J 0
(-4425 800);
DISPLAY 0.617021 (-4425 800);
PAINT SKYBLUE (-4425 800);
FORCEPROP 1 LASTPIN (-4475 850) $PN 2
J 0
(-4465 830);
DISPLAY 0.617021 (-4465 830);
PAINT GREEN (-4465 830);
FORCEPROP 1 LASTPIN (-4475 1050) $PN 1
J 0
(-4465 1030);
DISPLAY 0.617021 (-4465 1030);
PAINT GREEN (-4465 1030);
FORCEPROP 1 LAST VOLTAGE 4V
J 0
(-4425 950);
PAINT SKYBLUE (-4425 950);
DISPLAY INVISIBLE (-4425 950);
FORCEPROP 1 LAST MATERIAL X6S
J 0
(-4425 850);
PAINT SKYBLUE (-4425 850);
DISPLAY INVISIBLE (-4425 850);
FORCEPROP 2 LAST CDS_LIB mstr_discrete
J 0
(-4475 950);
PAINT ORANGE (-4475 950);
DISPLAY INVISIBLE (-4475 950);
FORCEPROP 2 LAST BOM_COST PROC
J 0
(-4475 950);
PAINT MONO (-4475 950);
DISPLAY INVISIBLE (-4475 950);
FORCEPROP 2 LAST CDS_SEC 1
J 0
(-4425 1150);
DISPLAY 1.021277 (-4425 1150);
PAINT ORANGE (-4425 1150);
DISPLAY INVISIBLE (-4425 1150);
FORCEPROP 2 LAST $SEC 1
J 0
(-4425 1150);
DISPLAY 0.680851 (-4425 1150);
PAINT MONO (-4425 1150);
DISPLAY INVISIBLE (-4425 1150);
FORCEPROP 2 LAST CDS_LOCATION C8P5
J 0
(-4425 1050);
DISPLAY 0.617021 (-4425 1050);
PAINT AQUA (-4425 1050);
DISPLAY INVISIBLE (-4425 1050);
FORCEPROP 1 LAST PATH I58
J 0
(-4425 1100);
DISPLAY 0.978723 (-4425 1100);
PAINT WHITE (-4425 1100);
DISPLAY INVISIBLE (-4425 1100);
FORCEPROP 2 LAST ROOM PVCCIN_CPU1_DECAP_VR
J 0
(-4425 1050);
PAINT ORANGE (-4425 1050);
DISPLAY INVISIBLE (-4425 1050);
FORCEADD CAP_A..1
(-4625 4425);
FORCEPROP 1 LAST LOCATION C2D12
J 0
(-4575 4525);
DISPLAY 0.617021 (-4575 4525);
PAINT AQUA (-4575 4525);
FORCEPROP 1 LAST PART_NUMBER E15431-004
J 0
(-4575 4275);
DISPLAY 0.617021 (-4575 4275);
PAINT BLUE (-4575 4275);
FORCEPROP 1 LAST VALUE 22.0UF
J 0
(-4575 4475);
DISPLAY 0.617021 (-4575 4475);
PAINT SKYBLUE (-4575 4475);
FORCEPROP 1 LAST TOLERANCE 20%
J 0
(-4575 4375);
DISPLAY 0.617021 (-4575 4375);
PAINT SKYBLUE (-4575 4375);
FORCEPROP 1 LAST PACK_TYPE 0603V
J 0
(-4575 4225);
DISPLAY 0.617021 (-4575 4225);
PAINT SKYBLUE (-4575 4225);
FORCEPROP 1 LAST VOLTAGE 4V
J 0
(-4575 4425);
DISPLAY 0.617021 (-4575 4425);
PAINT SKYBLUE (-4575 4425);
FORCEPROP 1 LAST MATERIAL X6S
J 0
(-4575 4325);
DISPLAY 0.617021 (-4575 4325);
PAINT SKYBLUE (-4575 4325);
FORCEPROP 1 LASTPIN (-4625 4525) $PN 1
J 0
(-4615 4505);
DISPLAY 0.617021 (-4615 4505);
PAINT GREEN (-4615 4505);
FORCEPROP 1 LASTPIN (-4625 4325) $PN 2
J 0
(-4615 4305);
DISPLAY 0.617021 (-4615 4305);
PAINT GREEN (-4615 4305);
FORCEPROP 2 LAST CDS_LOCATION C2D12
J 0
(-4575 4525);
DISPLAY 0.617021 (-4575 4525);
PAINT AQUA (-4575 4525);
DISPLAY INVISIBLE (-4575 4525);
FORCEPROP 2 LAST BOM_COST PROC
J 0
(-4625 4425);
PAINT MONO (-4625 4425);
DISPLAY INVISIBLE (-4625 4425);
FORCEPROP 2 LAST CDS_LIB dev_discrete
J 0
(-4625 4425);
PAINT ORANGE (-4625 4425);
DISPLAY INVISIBLE (-4625 4425);
FORCEPROP 2 LAST CDS_SEC 1
J 0
(-4575 4625);
PAINT MONO (-4575 4625);
DISPLAY INVISIBLE (-4575 4625);
FORCEPROP 2 LAST $SEC 1
J 0
(-4575 4625);
PAINT MONO (-4575 4625);
DISPLAY INVISIBLE (-4575 4625);
FORCEPROP 1 LAST PATH I59
J 0
(-4575 4575);
DISPLAY 0.978723 (-4575 4575);
PAINT WHITE (-4575 4575);
DISPLAY INVISIBLE (-4575 4575);
FORCEPROP 2 LAST ROOM PVCCIN_CPU1_DECAP_VR
J 0
(-4575 4525);
PAINT ORANGE (-4575 4525);
DISPLAY INVISIBLE (-4575 4525);
FORCEADD GND..1
(-4325 4125);
FORCEPROP 3 LASTPIN (-4325 4175) SIG_NAME GND\g
J 0
(-4315 4185);
DISPLAY 0.659574 (-4315 4185);
PAINT MONO (-4315 4185);
DISPLAY INVISIBLE (-4315 4185);
FORCEPROP 1 LAST VOLTAGE 0
J 0
(-4325 4125);
PAINT SKYBLUE (-4325 4125);
DISPLAY INVISIBLE (-4325 4125);
FORCEPROP 2 LAST CDS_LIB mstr_symbols
J 0
(-4325 4125);
PAINT ORANGE (-4325 4125);
DISPLAY INVISIBLE (-4325 4125);
FORCEPROP 1 LAST SIZE 1B
J 0
(-4250 4075);
DISPLAY 0.893617 (-4250 4075);
PAINT GREEN (-4250 4075);
DISPLAY INVISIBLE (-4250 4075);
FORCEPROP 1 LAST BODY_TYPE PLUMBING
J 0
(-4370 4082);
DISPLAY 0.340426 (-4370 4082);
PAINT GREEN (-4370 4082);
DISPLAY INVISIBLE (-4370 4082);
FORCEPROP 1 LAST PATH I60
J 0
(-4250 4125);
DISPLAY 0.872340 (-4250 4125);
PAINT AQUA (-4250 4125);
DISPLAY INVISIBLE (-4250 4125);
FORCEPROP 2 LAST ROOM PVCCIN_CPU1_DECAP_VR
J 0
(-4875 4200);
PAINT ORANGE (-4875 4200);
DISPLAY INVISIBLE (-4875 4200);
FORCEPROP 1 LAST HDL_POWER GND
J 0
(-4325 4275);
DISPLAY 0.893617 (-4325 4275);
PAINT GREEN (-4325 4275);
DISPLAY INVISIBLE (-4325 4275);
FORCEADD CAP_A..1
(-4950 4450);
FORCEPROP 1 LAST LOCATION C2D22
J 0
(-4900 4550);
DISPLAY 0.617021 (-4900 4550);
PAINT AQUA (-4900 4550);
FORCEPROP 1 LAST PART_NUMBER E15431-004
J 0
(-4900 4300);
DISPLAY 0.617021 (-4900 4300);
PAINT BLUE (-4900 4300);
FORCEPROP 1 LAST VALUE 22.0UF
J 0
(-4900 4500);
DISPLAY 0.617021 (-4900 4500);
PAINT SKYBLUE (-4900 4500);
FORCEPROP 1 LAST TOLERANCE 20%
J 0
(-4900 4400);
DISPLAY 0.617021 (-4900 4400);
PAINT SKYBLUE (-4900 4400);
FORCEPROP 1 LAST PACK_TYPE 0603V
J 0
(-4900 4250);
DISPLAY 0.617021 (-4900 4250);
PAINT SKYBLUE (-4900 4250);
FORCEPROP 1 LAST VOLTAGE 4V
J 0
(-4900 4450);
DISPLAY 0.617021 (-4900 4450);
PAINT SKYBLUE (-4900 4450);
FORCEPROP 1 LAST MATERIAL X6S
J 0
(-4900 4350);
DISPLAY 0.617021 (-4900 4350);
PAINT SKYBLUE (-4900 4350);
FORCEPROP 1 LASTPIN (-4950 4550) $PN 1
J 0
(-4940 4530);
DISPLAY 0.617021 (-4940 4530);
PAINT GREEN (-4940 4530);
FORCEPROP 1 LASTPIN (-4950 4350) $PN 2
J 0
(-4940 4330);
DISPLAY 0.617021 (-4940 4330);
PAINT GREEN (-4940 4330);
FORCEPROP 2 LAST CDS_LOCATION C2D22
J 0
(-4900 4550);
DISPLAY 0.617021 (-4900 4550);
PAINT AQUA (-4900 4550);
DISPLAY INVISIBLE (-4900 4550);
FORCEPROP 2 LAST BOM_COST PROC
J 0
(-4950 4450);
PAINT MONO (-4950 4450);
DISPLAY INVISIBLE (-4950 4450);
FORCEPROP 2 LAST CDS_LIB dev_discrete
J 0
(-4950 4450);
PAINT ORANGE (-4950 4450);
DISPLAY INVISIBLE (-4950 4450);
FORCEPROP 2 LAST CDS_SEC 1
J 0
(-4900 4650);
PAINT MONO (-4900 4650);
DISPLAY INVISIBLE (-4900 4650);
FORCEPROP 2 LAST $SEC 1
J 0
(-4900 4650);
PAINT MONO (-4900 4650);
DISPLAY INVISIBLE (-4900 4650);
FORCEPROP 1 LAST PATH I61
J 0
(-4900 4600);
DISPLAY 0.978723 (-4900 4600);
PAINT WHITE (-4900 4600);
DISPLAY INVISIBLE (-4900 4600);
FORCEPROP 2 LAST ROOM PVCCIN_CPU1_DECAP_VR
J 0
(-4900 4550);
PAINT ORANGE (-4900 4550);
DISPLAY INVISIBLE (-4900 4550);
FORCEADD CAP_A..1
(-5575 4450);
FORCEPROP 1 LAST LOCATION C2D31
J 0
(-5525 4550);
DISPLAY 0.617021 (-5525 4550);
PAINT AQUA (-5525 4550);
FORCEPROP 1 LAST PART_NUMBER E15431-004
J 0
(-5525 4300);
DISPLAY 0.617021 (-5525 4300);
PAINT BLUE (-5525 4300);
FORCEPROP 1 LAST VALUE 22.0UF
J 0
(-5525 4500);
DISPLAY 0.617021 (-5525 4500);
PAINT SKYBLUE (-5525 4500);
FORCEPROP 1 LAST TOLERANCE 20%
J 0
(-5525 4400);
DISPLAY 0.617021 (-5525 4400);
PAINT SKYBLUE (-5525 4400);
FORCEPROP 1 LAST PACK_TYPE 0603V
J 0
(-5525 4250);
DISPLAY 0.617021 (-5525 4250);
PAINT SKYBLUE (-5525 4250);
FORCEPROP 1 LAST VOLTAGE 4V
J 0
(-5525 4450);
DISPLAY 0.617021 (-5525 4450);
PAINT SKYBLUE (-5525 4450);
FORCEPROP 1 LAST MATERIAL X6S
J 0
(-5525 4350);
DISPLAY 0.617021 (-5525 4350);
PAINT SKYBLUE (-5525 4350);
FORCEPROP 1 LASTPIN (-5575 4550) $PN 1
J 0
(-5565 4530);
DISPLAY 0.617021 (-5565 4530);
PAINT GREEN (-5565 4530);
FORCEPROP 1 LASTPIN (-5575 4350) $PN 2
J 0
(-5565 4330);
DISPLAY 0.617021 (-5565 4330);
PAINT GREEN (-5565 4330);
FORCEPROP 2 LAST CDS_LOCATION C2D31
J 0
(-5525 4550);
DISPLAY 0.617021 (-5525 4550);
PAINT AQUA (-5525 4550);
DISPLAY INVISIBLE (-5525 4550);
FORCEPROP 2 LAST BOM_COST PROC
J 0
(-5575 4450);
PAINT MONO (-5575 4450);
DISPLAY INVISIBLE (-5575 4450);
FORCEPROP 2 LAST CDS_LIB dev_discrete
J 0
(-5575 4450);
PAINT ORANGE (-5575 4450);
DISPLAY INVISIBLE (-5575 4450);
FORCEPROP 2 LAST CDS_SEC 1
J 0
(-5525 4650);
PAINT MONO (-5525 4650);
DISPLAY INVISIBLE (-5525 4650);
FORCEPROP 2 LAST $SEC 1
J 0
(-5525 4650);
PAINT MONO (-5525 4650);
DISPLAY INVISIBLE (-5525 4650);
FORCEPROP 1 LAST PATH I63
J 0
(-5525 4600);
DISPLAY 0.978723 (-5525 4600);
PAINT WHITE (-5525 4600);
DISPLAY INVISIBLE (-5525 4600);
FORCEPROP 2 LAST ROOM PVCCIN_CPU1_DECAP_VR
J 0
(-5525 4550);
PAINT ORANGE (-5525 4550);
DISPLAY INVISIBLE (-5525 4550);
FORCEADD CAP_A..1
(-5900 4450);
FORCEPROP 1 LAST LOCATION C2D21
J 0
(-5850 4550);
DISPLAY 0.617021 (-5850 4550);
PAINT AQUA (-5850 4550);
FORCEPROP 1 LAST PART_NUMBER E15431-004
J 0
(-5850 4300);
DISPLAY 0.617021 (-5850 4300);
PAINT BLUE (-5850 4300);
FORCEPROP 1 LAST VALUE 22.0UF
J 0
(-5850 4500);
DISPLAY 0.617021 (-5850 4500);
PAINT SKYBLUE (-5850 4500);
FORCEPROP 1 LAST TOLERANCE 20%
J 0
(-5850 4400);
DISPLAY 0.617021 (-5850 4400);
PAINT SKYBLUE (-5850 4400);
FORCEPROP 1 LAST PACK_TYPE 0603V
J 0
(-5850 4250);
DISPLAY 0.617021 (-5850 4250);
PAINT SKYBLUE (-5850 4250);
FORCEPROP 1 LAST VOLTAGE 4V
J 0
(-5850 4450);
DISPLAY 0.617021 (-5850 4450);
PAINT SKYBLUE (-5850 4450);
FORCEPROP 1 LAST MATERIAL X6S
J 0
(-5850 4350);
DISPLAY 0.617021 (-5850 4350);
PAINT SKYBLUE (-5850 4350);
FORCEPROP 1 LASTPIN (-5900 4550) $PN 1
J 0
(-5890 4530);
DISPLAY 0.617021 (-5890 4530);
PAINT GREEN (-5890 4530);
FORCEPROP 1 LASTPIN (-5900 4350) $PN 2
J 0
(-5890 4330);
DISPLAY 0.617021 (-5890 4330);
PAINT GREEN (-5890 4330);
FORCEPROP 2 LAST CDS_LOCATION C2D21
J 0
(-5850 4550);
DISPLAY 0.617021 (-5850 4550);
PAINT AQUA (-5850 4550);
DISPLAY INVISIBLE (-5850 4550);
FORCEPROP 2 LAST BOM_COST PROC
J 0
(-5900 4450);
PAINT MONO (-5900 4450);
DISPLAY INVISIBLE (-5900 4450);
FORCEPROP 2 LAST CDS_LIB dev_discrete
J 0
(-5900 4450);
PAINT ORANGE (-5900 4450);
DISPLAY INVISIBLE (-5900 4450);
FORCEPROP 2 LAST CDS_SEC 1
J 0
(-5850 4650);
PAINT MONO (-5850 4650);
DISPLAY INVISIBLE (-5850 4650);
FORCEPROP 2 LAST $SEC 1
J 0
(-5850 4650);
PAINT MONO (-5850 4650);
DISPLAY INVISIBLE (-5850 4650);
FORCEPROP 1 LAST PATH I65
J 0
(-5850 4600);
DISPLAY 0.978723 (-5850 4600);
PAINT WHITE (-5850 4600);
DISPLAY INVISIBLE (-5850 4600);
FORCEPROP 2 LAST ROOM PVCCIN_CPU1_DECAP_VR
J 0
(-5850 4550);
PAINT ORANGE (-5850 4550);
DISPLAY INVISIBLE (-5850 4550);
FORCEADD CAP_A..1
(-6350 4450);
FORCEPROP 1 LAST LOCATION C2D27
J 0
(-6300 4550);
DISPLAY 0.617021 (-6300 4550);
PAINT AQUA (-6300 4550);
FORCEPROP 1 LAST PART_NUMBER E15431-004
J 0
(-6300 4300);
DISPLAY 0.617021 (-6300 4300);
PAINT BLUE (-6300 4300);
FORCEPROP 1 LAST VALUE 22.0UF
J 0
(-6300 4500);
DISPLAY 0.617021 (-6300 4500);
PAINT SKYBLUE (-6300 4500);
FORCEPROP 1 LAST TOLERANCE 20%
J 0
(-6300 4400);
DISPLAY 0.617021 (-6300 4400);
PAINT SKYBLUE (-6300 4400);
FORCEPROP 1 LAST PACK_TYPE 0603V
J 0
(-6300 4250);
DISPLAY 0.617021 (-6300 4250);
PAINT SKYBLUE (-6300 4250);
FORCEPROP 1 LAST VOLTAGE 4V
J 0
(-6300 4450);
DISPLAY 0.617021 (-6300 4450);
PAINT SKYBLUE (-6300 4450);
FORCEPROP 1 LAST MATERIAL X6S
J 0
(-6300 4350);
DISPLAY 0.617021 (-6300 4350);
PAINT SKYBLUE (-6300 4350);
FORCEPROP 1 LASTPIN (-6350 4550) $PN 1
J 0
(-6340 4530);
DISPLAY 0.617021 (-6340 4530);
PAINT GREEN (-6340 4530);
FORCEPROP 1 LASTPIN (-6350 4350) $PN 2
J 0
(-6340 4330);
DISPLAY 0.617021 (-6340 4330);
PAINT GREEN (-6340 4330);
FORCEPROP 2 LAST CDS_LOCATION C2D27
J 0
(-6300 4550);
DISPLAY 0.617021 (-6300 4550);
PAINT AQUA (-6300 4550);
DISPLAY INVISIBLE (-6300 4550);
FORCEPROP 2 LAST BOM_COST PROC
J 0
(-6350 4450);
PAINT MONO (-6350 4450);
DISPLAY INVISIBLE (-6350 4450);
FORCEPROP 2 LAST CDS_LIB dev_discrete
J 0
(-6350 4450);
PAINT ORANGE (-6350 4450);
DISPLAY INVISIBLE (-6350 4450);
FORCEPROP 2 LAST CDS_SEC 1
J 0
(-6300 4650);
PAINT MONO (-6300 4650);
DISPLAY INVISIBLE (-6300 4650);
FORCEPROP 2 LAST $SEC 1
J 0
(-6300 4650);
PAINT MONO (-6300 4650);
DISPLAY INVISIBLE (-6300 4650);
FORCEPROP 1 LAST PATH I66
J 0
(-6300 4600);
DISPLAY 0.978723 (-6300 4600);
PAINT WHITE (-6300 4600);
DISPLAY INVISIBLE (-6300 4600);
FORCEPROP 2 LAST ROOM PVCCIN_CPU1_DECAP_VR
J 0
(-6300 4550);
PAINT ORANGE (-6300 4550);
DISPLAY INVISIBLE (-6300 4550);
FORCEADD GND..1
(-6350 4125);
FORCEPROP 3 LASTPIN (-6350 4175) SIG_NAME GND\g
J 0
(-6340 4185);
DISPLAY 0.659574 (-6340 4185);
PAINT MONO (-6340 4185);
DISPLAY INVISIBLE (-6340 4185);
FORCEPROP 1 LAST VOLTAGE 0
J 0
(-6350 4125);
PAINT SKYBLUE (-6350 4125);
DISPLAY INVISIBLE (-6350 4125);
FORCEPROP 2 LAST CDS_LIB mstr_symbols
J 0
(-6350 4125);
PAINT ORANGE (-6350 4125);
DISPLAY INVISIBLE (-6350 4125);
FORCEPROP 1 LAST SIZE 1B
J 0
(-6275 4075);
DISPLAY 0.893617 (-6275 4075);
PAINT GREEN (-6275 4075);
DISPLAY INVISIBLE (-6275 4075);
FORCEPROP 1 LAST BODY_TYPE PLUMBING
J 0
(-6395 4082);
DISPLAY 0.340426 (-6395 4082);
PAINT GREEN (-6395 4082);
DISPLAY INVISIBLE (-6395 4082);
FORCEPROP 1 LAST PATH I67
J 0
(-6275 4125);
DISPLAY 0.872340 (-6275 4125);
PAINT AQUA (-6275 4125);
DISPLAY INVISIBLE (-6275 4125);
FORCEPROP 2 LAST ROOM PVCCIN_CPU1_DECAP_VR
J 0
(-6900 4200);
PAINT ORANGE (-6900 4200);
DISPLAY INVISIBLE (-6900 4200);
FORCEPROP 1 LAST HDL_POWER GND
J 0
(-6350 4275);
DISPLAY 0.893617 (-6350 4275);
PAINT GREEN (-6350 4275);
DISPLAY INVISIBLE (-6350 4275);
FORCEADD CAP_A..1
(-7050 4450);
FORCEPROP 1 LAST LOCATION C3D2
J 0
(-7000 4550);
DISPLAY 0.617021 (-7000 4550);
PAINT AQUA (-7000 4550);
FORCEPROP 1 LAST PART_NUMBER E15431-004
J 0
(-7000 4300);
DISPLAY 0.617021 (-7000 4300);
PAINT BLUE (-7000 4300);
FORCEPROP 1 LAST VALUE 22.0UF
J 0
(-7000 4500);
DISPLAY 0.617021 (-7000 4500);
PAINT SKYBLUE (-7000 4500);
FORCEPROP 1 LAST TOLERANCE 20%
J 0
(-7000 4400);
DISPLAY 0.617021 (-7000 4400);
PAINT SKYBLUE (-7000 4400);
FORCEPROP 1 LAST PACK_TYPE 0603V
J 0
(-7000 4250);
DISPLAY 0.617021 (-7000 4250);
PAINT SKYBLUE (-7000 4250);
FORCEPROP 1 LAST VOLTAGE 4V
J 0
(-7000 4450);
DISPLAY 0.617021 (-7000 4450);
PAINT SKYBLUE (-7000 4450);
FORCEPROP 1 LAST MATERIAL X6S
J 0
(-7000 4350);
DISPLAY 0.617021 (-7000 4350);
PAINT SKYBLUE (-7000 4350);
FORCEPROP 1 LASTPIN (-7050 4550) $PN 1
J 0
(-7040 4530);
DISPLAY 0.617021 (-7040 4530);
PAINT GREEN (-7040 4530);
FORCEPROP 1 LASTPIN (-7050 4350) $PN 2
J 0
(-7040 4330);
DISPLAY 0.617021 (-7040 4330);
PAINT GREEN (-7040 4330);
FORCEPROP 2 LAST CDS_LOCATION C3D2
J 0
(-7000 4550);
DISPLAY 0.617021 (-7000 4550);
PAINT AQUA (-7000 4550);
DISPLAY INVISIBLE (-7000 4550);
FORCEPROP 2 LAST BOM_COST PROC
J 0
(-7050 4450);
PAINT MONO (-7050 4450);
DISPLAY INVISIBLE (-7050 4450);
FORCEPROP 2 LAST CDS_LIB dev_discrete
J 0
(-7050 4450);
PAINT ORANGE (-7050 4450);
DISPLAY INVISIBLE (-7050 4450);
FORCEPROP 2 LAST CDS_SEC 1
J 0
(-7000 4650);
PAINT MONO (-7000 4650);
DISPLAY INVISIBLE (-7000 4650);
FORCEPROP 2 LAST $SEC 1
J 0
(-7000 4650);
PAINT MONO (-7000 4650);
DISPLAY INVISIBLE (-7000 4650);
FORCEPROP 1 LAST PATH I69
J 0
(-7000 4600);
DISPLAY 0.978723 (-7000 4600);
PAINT WHITE (-7000 4600);
DISPLAY INVISIBLE (-7000 4600);
FORCEPROP 2 LAST ROOM PVCCIN_CPU1_DECAP_VR
J 0
(-7000 4550);
PAINT ORANGE (-7000 4550);
DISPLAY INVISIBLE (-7000 4550);
FORCEADD CAP_A..1
(-2450 4450);
FORCEPROP 1 LAST LOCATION C3D11
J 0
(-2400 4550);
DISPLAY 0.617021 (-2400 4550);
PAINT AQUA (-2400 4550);
FORCEPROP 1 LAST PART_NUMBER E15431-004
J 0
(-2400 4300);
DISPLAY 0.617021 (-2400 4300);
PAINT BLUE (-2400 4300);
FORCEPROP 1 LAST VALUE 22.0UF
J 0
(-2400 4500);
DISPLAY 0.617021 (-2400 4500);
PAINT SKYBLUE (-2400 4500);
FORCEPROP 1 LAST TOLERANCE 20%
J 0
(-2400 4400);
DISPLAY 0.617021 (-2400 4400);
PAINT SKYBLUE (-2400 4400);
FORCEPROP 1 LAST PACK_TYPE 0603V
J 0
(-2400 4250);
DISPLAY 0.617021 (-2400 4250);
PAINT SKYBLUE (-2400 4250);
FORCEPROP 1 LAST VOLTAGE 4V
J 0
(-2400 4450);
DISPLAY 0.617021 (-2400 4450);
PAINT SKYBLUE (-2400 4450);
FORCEPROP 1 LAST MATERIAL X6S
J 0
(-2400 4350);
DISPLAY 0.617021 (-2400 4350);
PAINT SKYBLUE (-2400 4350);
FORCEPROP 1 LASTPIN (-2450 4550) $PN 1
J 0
(-2440 4530);
DISPLAY 0.617021 (-2440 4530);
PAINT GREEN (-2440 4530);
FORCEPROP 1 LASTPIN (-2450 4350) $PN 2
J 0
(-2440 4330);
DISPLAY 0.617021 (-2440 4330);
PAINT GREEN (-2440 4330);
FORCEPROP 2 LAST CDS_LOCATION C3D11
J 0
(-2400 4550);
DISPLAY 0.617021 (-2400 4550);
PAINT AQUA (-2400 4550);
DISPLAY INVISIBLE (-2400 4550);
FORCEPROP 2 LAST BOM_COST PROC
J 0
(-2450 4450);
PAINT MONO (-2450 4450);
DISPLAY INVISIBLE (-2450 4450);
FORCEPROP 2 LAST CDS_LIB dev_discrete
J 0
(-2450 4450);
PAINT ORANGE (-2450 4450);
DISPLAY INVISIBLE (-2450 4450);
FORCEPROP 2 LAST CDS_SEC 1
J 0
(-2400 4650);
PAINT MONO (-2400 4650);
DISPLAY INVISIBLE (-2400 4650);
FORCEPROP 2 LAST $SEC 1
J 0
(-2400 4650);
PAINT MONO (-2400 4650);
DISPLAY INVISIBLE (-2400 4650);
FORCEPROP 1 LAST PATH I7
J 0
(-2400 4600);
DISPLAY 0.978723 (-2400 4600);
PAINT WHITE (-2400 4600);
DISPLAY INVISIBLE (-2400 4600);
FORCEPROP 2 LAST ROOM PVCCIN_CPU1_DECAP_VR
J 0
(-2400 4550);
PAINT ORANGE (-2400 4550);
DISPLAY INVISIBLE (-2400 4550);
FORCEADD CAP_A..1
(-7375 4450);
FORCEPROP 1 LAST LOCATION C2D36
J 0
(-7325 4550);
DISPLAY 0.617021 (-7325 4550);
PAINT AQUA (-7325 4550);
FORCEPROP 1 LAST PART_NUMBER E15431-004
J 0
(-7325 4300);
DISPLAY 0.617021 (-7325 4300);
PAINT BLUE (-7325 4300);
FORCEPROP 1 LAST VALUE 22.0UF
J 0
(-7325 4500);
DISPLAY 0.617021 (-7325 4500);
PAINT SKYBLUE (-7325 4500);
FORCEPROP 1 LAST TOLERANCE 20%
J 0
(-7325 4400);
DISPLAY 0.617021 (-7325 4400);
PAINT SKYBLUE (-7325 4400);
FORCEPROP 1 LAST PACK_TYPE 0603V
J 0
(-7325 4250);
DISPLAY 0.617021 (-7325 4250);
PAINT SKYBLUE (-7325 4250);
FORCEPROP 1 LAST VOLTAGE 4V
J 0
(-7325 4450);
DISPLAY 0.617021 (-7325 4450);
PAINT SKYBLUE (-7325 4450);
FORCEPROP 1 LAST MATERIAL X6S
J 0
(-7325 4350);
DISPLAY 0.617021 (-7325 4350);
PAINT SKYBLUE (-7325 4350);
FORCEPROP 1 LASTPIN (-7375 4550) $PN 1
J 0
(-7365 4530);
DISPLAY 0.617021 (-7365 4530);
PAINT GREEN (-7365 4530);
FORCEPROP 1 LASTPIN (-7375 4350) $PN 2
J 0
(-7365 4330);
DISPLAY 0.617021 (-7365 4330);
PAINT GREEN (-7365 4330);
FORCEPROP 2 LAST CDS_LOCATION C2D36
J 0
(-7325 4550);
DISPLAY 0.617021 (-7325 4550);
PAINT AQUA (-7325 4550);
DISPLAY INVISIBLE (-7325 4550);
FORCEPROP 2 LAST BOM_COST PROC
J 0
(-7375 4450);
PAINT MONO (-7375 4450);
DISPLAY INVISIBLE (-7375 4450);
FORCEPROP 2 LAST CDS_LIB dev_discrete
J 0
(-7375 4450);
PAINT ORANGE (-7375 4450);
DISPLAY INVISIBLE (-7375 4450);
FORCEPROP 2 LAST CDS_SEC 1
J 0
(-7325 4650);
PAINT MONO (-7325 4650);
DISPLAY INVISIBLE (-7325 4650);
FORCEPROP 2 LAST $SEC 1
J 0
(-7325 4650);
PAINT MONO (-7325 4650);
DISPLAY INVISIBLE (-7325 4650);
FORCEPROP 1 LAST PATH I70
J 0
(-7325 4600);
DISPLAY 0.978723 (-7325 4600);
PAINT WHITE (-7325 4600);
DISPLAY INVISIBLE (-7325 4600);
FORCEPROP 2 LAST ROOM PVCCIN_CPU1_DECAP_VR
J 0
(-7325 4550);
PAINT ORANGE (-7325 4550);
DISPLAY INVISIBLE (-7325 4550);
FORCEADD PVCCIN_CPU1..1
(-7725 4725);
FORCEPROP 3 LASTPIN (-7725 4675) SIG_NAME PVCCIN_CPU1\g
J 0
(-7715 4685);
DISPLAY 0.659574 (-7715 4685);
PAINT MONO (-7715 4685);
DISPLAY INVISIBLE (-7715 4685);
FORCEPROP 1 LAST VOLTAGE 2.0V
J 0
(-7770 4682);
DISPLAY 0.340426 (-7770 4682);
PAINT SKYBLUE (-7770 4682);
DISPLAY INVISIBLE (-7770 4682);
FORCEPROP 2 LAST CDS_LIB mstr_symbols
J 0
(-7725 4725);
PAINT ORANGE (-7725 4725);
DISPLAY INVISIBLE (-7725 4725);
FORCEPROP 1 LAST BODY_TYPE PLUMBING
J 0
(-7770 4682);
DISPLAY 0.340426 (-7770 4682);
PAINT GREEN (-7770 4682);
DISPLAY INVISIBLE (-7770 4682);
FORCEPROP 1 LAST PATH I71
J 0
(-7675 4750);
DISPLAY 0.872340 (-7675 4750);
PAINT AQUA (-7675 4750);
DISPLAY INVISIBLE (-7675 4750);
FORCEPROP 2 LAST ROOM PVCCIN_CPU1_DECAP_VR
J 0
(-7475 4825);
PAINT ORANGE (-7475 4825);
DISPLAY INVISIBLE (-7475 4825);
FORCEPROP 1 LAST HDL_POWER PVCCIN_CPU1
J 1
(-7725 4775);
DISPLAY 0.872340 (-7725 4775);
PAINT GREEN (-7725 4775);
DISPLAY INVISIBLE (-7725 4775);
FORCEADD CAP_A..1
(-4625 3750);
FORCEPROP 1 LAST LOCATION C2D13
J 0
(-4575 3850);
DISPLAY 0.617021 (-4575 3850);
PAINT AQUA (-4575 3850);
FORCEPROP 1 LAST PART_NUMBER E15431-004
J 0
(-4575 3600);
DISPLAY 0.617021 (-4575 3600);
PAINT BLUE (-4575 3600);
FORCEPROP 1 LAST VALUE 22.0UF
J 0
(-4575 3800);
DISPLAY 0.617021 (-4575 3800);
PAINT SKYBLUE (-4575 3800);
FORCEPROP 1 LAST TOLERANCE 20%
J 0
(-4575 3700);
DISPLAY 0.617021 (-4575 3700);
PAINT SKYBLUE (-4575 3700);
FORCEPROP 1 LAST PACK_TYPE 0603V
J 0
(-4575 3550);
DISPLAY 0.617021 (-4575 3550);
PAINT SKYBLUE (-4575 3550);
FORCEPROP 1 LAST VOLTAGE 4V
J 0
(-4575 3750);
DISPLAY 0.617021 (-4575 3750);
PAINT SKYBLUE (-4575 3750);
FORCEPROP 1 LAST MATERIAL X6S
J 0
(-4575 3650);
DISPLAY 0.617021 (-4575 3650);
PAINT SKYBLUE (-4575 3650);
FORCEPROP 1 LASTPIN (-4625 3850) $PN 1
J 0
(-4615 3830);
DISPLAY 0.617021 (-4615 3830);
PAINT GREEN (-4615 3830);
FORCEPROP 1 LASTPIN (-4625 3650) $PN 2
J 0
(-4615 3630);
DISPLAY 0.617021 (-4615 3630);
PAINT GREEN (-4615 3630);
FORCEPROP 2 LAST CDS_LOCATION C2D13
J 0
(-4575 3850);
DISPLAY 0.617021 (-4575 3850);
PAINT AQUA (-4575 3850);
DISPLAY INVISIBLE (-4575 3850);
FORCEPROP 2 LAST BOM_COST PROC
J 0
(-4625 3750);
PAINT MONO (-4625 3750);
DISPLAY INVISIBLE (-4625 3750);
FORCEPROP 2 LAST CDS_LIB dev_discrete
J 0
(-4625 3750);
PAINT ORANGE (-4625 3750);
DISPLAY INVISIBLE (-4625 3750);
FORCEPROP 2 LAST CDS_SEC 1
J 0
(-4575 3950);
PAINT MONO (-4575 3950);
DISPLAY INVISIBLE (-4575 3950);
FORCEPROP 2 LAST $SEC 1
J 0
(-4575 3950);
PAINT MONO (-4575 3950);
DISPLAY INVISIBLE (-4575 3950);
FORCEPROP 1 LAST PATH I73
J 0
(-4575 3900);
DISPLAY 0.978723 (-4575 3900);
PAINT WHITE (-4575 3900);
DISPLAY INVISIBLE (-4575 3900);
FORCEPROP 2 LAST ROOM PVCCIN_CPU1_DECAP_VR
J 0
(-4575 3850);
PAINT ORANGE (-4575 3850);
DISPLAY INVISIBLE (-4575 3850);
FORCEADD GND..1
(-4325 3450);
FORCEPROP 3 LASTPIN (-4325 3500) SIG_NAME GND\g
J 0
(-4315 3510);
DISPLAY 0.659574 (-4315 3510);
PAINT MONO (-4315 3510);
DISPLAY INVISIBLE (-4315 3510);
FORCEPROP 1 LAST VOLTAGE 0
J 0
(-4325 3450);
PAINT SKYBLUE (-4325 3450);
DISPLAY INVISIBLE (-4325 3450);
FORCEPROP 1 LAST SIZE 1B
J 0
(-4250 3400);
DISPLAY 0.893617 (-4250 3400);
PAINT GREEN (-4250 3400);
DISPLAY INVISIBLE (-4250 3400);
FORCEPROP 2 LAST CDS_LIB mstr_symbols
J 0
(-4325 3450);
PAINT ORANGE (-4325 3450);
DISPLAY INVISIBLE (-4325 3450);
FORCEPROP 1 LAST BODY_TYPE PLUMBING
J 0
(-4370 3407);
DISPLAY 0.340426 (-4370 3407);
PAINT GREEN (-4370 3407);
DISPLAY INVISIBLE (-4370 3407);
FORCEPROP 1 LAST PATH I74
J 0
(-4250 3450);
DISPLAY 0.872340 (-4250 3450);
PAINT AQUA (-4250 3450);
DISPLAY INVISIBLE (-4250 3450);
FORCEPROP 2 LAST ROOM PVCCIN_CPU1_DECAP_VR
J 0
(-4875 3525);
PAINT ORANGE (-4875 3525);
DISPLAY INVISIBLE (-4875 3525);
FORCEPROP 1 LAST HDL_POWER GND
J 0
(-4325 3600);
DISPLAY 0.893617 (-4325 3600);
PAINT GREEN (-4325 3600);
DISPLAY INVISIBLE (-4325 3600);
FORCEADD CAP_A..1
(-4900 3775);
FORCEPROP 1 LAST LOCATION C2D19
J 0
(-4850 3875);
DISPLAY 0.617021 (-4850 3875);
PAINT AQUA (-4850 3875);
FORCEPROP 1 LAST PART_NUMBER E15431-004
J 0
(-4850 3625);
DISPLAY 0.617021 (-4850 3625);
PAINT BLUE (-4850 3625);
FORCEPROP 1 LAST VALUE 22.0UF
J 0
(-4850 3825);
DISPLAY 0.617021 (-4850 3825);
PAINT SKYBLUE (-4850 3825);
FORCEPROP 1 LAST TOLERANCE 20%
J 0
(-4850 3725);
DISPLAY 0.617021 (-4850 3725);
PAINT SKYBLUE (-4850 3725);
FORCEPROP 1 LAST PACK_TYPE 0603V
J 0
(-4850 3575);
DISPLAY 0.617021 (-4850 3575);
PAINT SKYBLUE (-4850 3575);
FORCEPROP 1 LAST VOLTAGE 4V
J 0
(-4850 3775);
DISPLAY 0.617021 (-4850 3775);
PAINT SKYBLUE (-4850 3775);
FORCEPROP 1 LAST MATERIAL X6S
J 0
(-4850 3675);
DISPLAY 0.617021 (-4850 3675);
PAINT SKYBLUE (-4850 3675);
FORCEPROP 1 LASTPIN (-4900 3875) $PN 1
J 0
(-4890 3855);
DISPLAY 0.617021 (-4890 3855);
PAINT GREEN (-4890 3855);
FORCEPROP 1 LASTPIN (-4900 3675) $PN 2
J 0
(-4890 3655);
DISPLAY 0.617021 (-4890 3655);
PAINT GREEN (-4890 3655);
FORCEPROP 2 LAST CDS_LOCATION C2D19
J 0
(-4850 3875);
DISPLAY 0.617021 (-4850 3875);
PAINT AQUA (-4850 3875);
DISPLAY INVISIBLE (-4850 3875);
FORCEPROP 2 LAST BOM_COST PROC
J 0
(-4900 3775);
PAINT MONO (-4900 3775);
DISPLAY INVISIBLE (-4900 3775);
FORCEPROP 2 LAST CDS_LIB dev_discrete
J 0
(-4900 3775);
PAINT ORANGE (-4900 3775);
DISPLAY INVISIBLE (-4900 3775);
FORCEPROP 2 LAST CDS_SEC 1
J 0
(-4850 3975);
PAINT MONO (-4850 3975);
DISPLAY INVISIBLE (-4850 3975);
FORCEPROP 2 LAST $SEC 1
J 0
(-4850 3975);
PAINT MONO (-4850 3975);
DISPLAY INVISIBLE (-4850 3975);
FORCEPROP 1 LAST PATH I75
J 0
(-4850 3925);
DISPLAY 0.978723 (-4850 3925);
PAINT WHITE (-4850 3925);
DISPLAY INVISIBLE (-4850 3925);
FORCEPROP 2 LAST ROOM PVCCIN_CPU1_DECAP_VR
J 0
(-4850 3875);
PAINT ORANGE (-4850 3875);
DISPLAY INVISIBLE (-4850 3875);
FORCEADD CAP_A..1
(-4600 3150);
FORCEPROP 1 LAST LOCATION C2D14
J 0
(-4550 3250);
DISPLAY 0.617021 (-4550 3250);
PAINT AQUA (-4550 3250);
FORCEPROP 1 LAST PART_NUMBER E15431-004
J 0
(-4550 3000);
DISPLAY 0.617021 (-4550 3000);
PAINT BLUE (-4550 3000);
FORCEPROP 1 LAST VALUE 22.0UF
J 0
(-4550 3200);
DISPLAY 0.617021 (-4550 3200);
PAINT SKYBLUE (-4550 3200);
FORCEPROP 1 LAST TOLERANCE 20%
J 0
(-4550 3100);
DISPLAY 0.617021 (-4550 3100);
PAINT SKYBLUE (-4550 3100);
FORCEPROP 1 LAST PACK_TYPE 0603V
J 0
(-4550 2950);
DISPLAY 0.617021 (-4550 2950);
PAINT SKYBLUE (-4550 2950);
FORCEPROP 1 LAST VOLTAGE 4V
J 0
(-4550 3150);
DISPLAY 0.617021 (-4550 3150);
PAINT SKYBLUE (-4550 3150);
FORCEPROP 1 LAST MATERIAL X6S
J 0
(-4550 3050);
DISPLAY 0.617021 (-4550 3050);
PAINT SKYBLUE (-4550 3050);
FORCEPROP 1 LASTPIN (-4600 3250) $PN 1
J 0
(-4590 3230);
DISPLAY 0.617021 (-4590 3230);
PAINT GREEN (-4590 3230);
FORCEPROP 1 LASTPIN (-4600 3050) $PN 2
J 0
(-4590 3030);
DISPLAY 0.617021 (-4590 3030);
PAINT GREEN (-4590 3030);
FORCEPROP 2 LAST CDS_LOCATION C2D14
J 0
(-4550 3250);
DISPLAY 0.617021 (-4550 3250);
PAINT AQUA (-4550 3250);
DISPLAY INVISIBLE (-4550 3250);
FORCEPROP 2 LAST BOM_COST PROC
J 0
(-4600 3150);
PAINT MONO (-4600 3150);
DISPLAY INVISIBLE (-4600 3150);
FORCEPROP 2 LAST CDS_LIB dev_discrete
J 0
(-4600 3150);
PAINT ORANGE (-4600 3150);
DISPLAY INVISIBLE (-4600 3150);
FORCEPROP 2 LAST CDS_SEC 1
J 0
(-4550 3350);
PAINT MONO (-4550 3350);
DISPLAY INVISIBLE (-4550 3350);
FORCEPROP 2 LAST $SEC 1
J 0
(-4550 3350);
PAINT MONO (-4550 3350);
DISPLAY INVISIBLE (-4550 3350);
FORCEPROP 1 LAST PATH I76
J 0
(-4550 3300);
DISPLAY 0.978723 (-4550 3300);
PAINT WHITE (-4550 3300);
DISPLAY INVISIBLE (-4550 3300);
FORCEPROP 2 LAST ROOM PVCCIN_CPU1_DECAP_VR
J 0
(-4550 3250);
PAINT ORANGE (-4550 3250);
DISPLAY INVISIBLE (-4550 3250);
FORCEADD GND..1
(-4325 2850);
FORCEPROP 3 LASTPIN (-4325 2900) SIG_NAME GND\g
J 0
(-4315 2910);
DISPLAY 0.659574 (-4315 2910);
PAINT MONO (-4315 2910);
DISPLAY INVISIBLE (-4315 2910);
FORCEPROP 1 LAST VOLTAGE 0
J 0
(-4325 2850);
PAINT SKYBLUE (-4325 2850);
DISPLAY INVISIBLE (-4325 2850);
FORCEPROP 1 LAST SIZE 1B
J 0
(-4250 2800);
DISPLAY 0.893617 (-4250 2800);
PAINT GREEN (-4250 2800);
DISPLAY INVISIBLE (-4250 2800);
FORCEPROP 2 LAST CDS_LIB mstr_symbols
J 0
(-4325 2850);
PAINT ORANGE (-4325 2850);
DISPLAY INVISIBLE (-4325 2850);
FORCEPROP 1 LAST BODY_TYPE PLUMBING
J 0
(-4370 2807);
DISPLAY 0.340426 (-4370 2807);
PAINT GREEN (-4370 2807);
DISPLAY INVISIBLE (-4370 2807);
FORCEPROP 1 LAST PATH I77
J 0
(-4250 2850);
DISPLAY 0.872340 (-4250 2850);
PAINT AQUA (-4250 2850);
DISPLAY INVISIBLE (-4250 2850);
FORCEPROP 2 LAST ROOM PVCCIN_CPU1_DECAP_VR
J 0
(-4875 2925);
PAINT ORANGE (-4875 2925);
DISPLAY INVISIBLE (-4875 2925);
FORCEPROP 1 LAST HDL_POWER GND
J 0
(-4325 3000);
DISPLAY 0.893617 (-4325 3000);
PAINT GREEN (-4325 3000);
DISPLAY INVISIBLE (-4325 3000);
FORCEADD CAP_A..1
(-4875 3125);
FORCEPROP 1 LAST LOCATION C2D20
J 0
(-4825 3225);
DISPLAY 0.617021 (-4825 3225);
PAINT AQUA (-4825 3225);
FORCEPROP 1 LAST PART_NUMBER E15431-004
J 0
(-4825 2975);
DISPLAY 0.617021 (-4825 2975);
PAINT BLUE (-4825 2975);
FORCEPROP 1 LAST VALUE 22.0UF
J 0
(-4825 3175);
DISPLAY 0.617021 (-4825 3175);
PAINT SKYBLUE (-4825 3175);
FORCEPROP 1 LAST TOLERANCE 20%
J 0
(-4825 3075);
DISPLAY 0.617021 (-4825 3075);
PAINT SKYBLUE (-4825 3075);
FORCEPROP 1 LAST PACK_TYPE 0603V
J 0
(-4825 2925);
DISPLAY 0.617021 (-4825 2925);
PAINT SKYBLUE (-4825 2925);
FORCEPROP 1 LAST VOLTAGE 4V
J 0
(-4825 3125);
DISPLAY 0.617021 (-4825 3125);
PAINT SKYBLUE (-4825 3125);
FORCEPROP 1 LAST MATERIAL X6S
J 0
(-4825 3025);
DISPLAY 0.617021 (-4825 3025);
PAINT SKYBLUE (-4825 3025);
FORCEPROP 1 LASTPIN (-4875 3225) $PN 1
J 0
(-4865 3205);
DISPLAY 0.617021 (-4865 3205);
PAINT GREEN (-4865 3205);
FORCEPROP 1 LASTPIN (-4875 3025) $PN 2
J 0
(-4865 3005);
DISPLAY 0.617021 (-4865 3005);
PAINT GREEN (-4865 3005);
FORCEPROP 2 LAST CDS_LOCATION C2D20
J 0
(-4825 3225);
DISPLAY 0.617021 (-4825 3225);
PAINT AQUA (-4825 3225);
DISPLAY INVISIBLE (-4825 3225);
FORCEPROP 2 LAST BOM_COST PROC
J 0
(-4875 3125);
PAINT MONO (-4875 3125);
DISPLAY INVISIBLE (-4875 3125);
FORCEPROP 2 LAST CDS_LIB dev_discrete
J 0
(-4875 3125);
PAINT ORANGE (-4875 3125);
DISPLAY INVISIBLE (-4875 3125);
FORCEPROP 2 LAST CDS_SEC 1
J 0
(-4825 3325);
PAINT MONO (-4825 3325);
DISPLAY INVISIBLE (-4825 3325);
FORCEPROP 2 LAST $SEC 1
J 0
(-4825 3325);
PAINT MONO (-4825 3325);
DISPLAY INVISIBLE (-4825 3325);
FORCEPROP 1 LAST PATH I79
J 0
(-4825 3275);
DISPLAY 0.978723 (-4825 3275);
PAINT WHITE (-4825 3275);
DISPLAY INVISIBLE (-4825 3275);
FORCEPROP 2 LAST ROOM PVCCIN_CPU1_DECAP_VR
J 0
(-4825 3225);
PAINT ORANGE (-4825 3225);
DISPLAY INVISIBLE (-4825 3225);
FORCEADD CAP_A..1
(-2975 4450);
FORCEPROP 1 LAST LOCATION C3D13
J 0
(-2925 4550);
DISPLAY 0.617021 (-2925 4550);
PAINT AQUA (-2925 4550);
FORCEPROP 1 LAST PART_NUMBER E15431-004
J 0
(-2925 4300);
DISPLAY 0.617021 (-2925 4300);
PAINT BLUE (-2925 4300);
FORCEPROP 1 LAST VALUE 22.0UF
J 0
(-2925 4500);
DISPLAY 0.617021 (-2925 4500);
PAINT SKYBLUE (-2925 4500);
FORCEPROP 1 LAST TOLERANCE 20%
J 0
(-2925 4400);
DISPLAY 0.617021 (-2925 4400);
PAINT SKYBLUE (-2925 4400);
FORCEPROP 1 LAST PACK_TYPE 0603V
J 0
(-2925 4250);
DISPLAY 0.617021 (-2925 4250);
PAINT SKYBLUE (-2925 4250);
FORCEPROP 1 LAST VOLTAGE 4V
J 0
(-2925 4450);
DISPLAY 0.617021 (-2925 4450);
PAINT SKYBLUE (-2925 4450);
FORCEPROP 1 LAST MATERIAL X6S
J 0
(-2925 4350);
DISPLAY 0.617021 (-2925 4350);
PAINT SKYBLUE (-2925 4350);
FORCEPROP 1 LASTPIN (-2975 4550) $PN 1
J 0
(-2965 4530);
DISPLAY 0.617021 (-2965 4530);
PAINT GREEN (-2965 4530);
FORCEPROP 1 LASTPIN (-2975 4350) $PN 2
J 0
(-2965 4330);
DISPLAY 0.617021 (-2965 4330);
PAINT GREEN (-2965 4330);
FORCEPROP 2 LAST CDS_LOCATION C3D13
J 0
(-2925 4550);
DISPLAY 0.617021 (-2925 4550);
PAINT AQUA (-2925 4550);
DISPLAY INVISIBLE (-2925 4550);
FORCEPROP 2 LAST BOM_COST PROC
J 0
(-2975 4450);
PAINT MONO (-2975 4450);
DISPLAY INVISIBLE (-2975 4450);
FORCEPROP 2 LAST CDS_LIB dev_discrete
J 0
(-2975 4450);
PAINT ORANGE (-2975 4450);
DISPLAY INVISIBLE (-2975 4450);
FORCEPROP 2 LAST CDS_SEC 1
J 0
(-2925 4650);
PAINT MONO (-2925 4650);
DISPLAY INVISIBLE (-2925 4650);
FORCEPROP 2 LAST $SEC 1
J 0
(-2925 4650);
PAINT MONO (-2925 4650);
DISPLAY INVISIBLE (-2925 4650);
FORCEPROP 1 LAST PATH I8
J 0
(-2925 4600);
DISPLAY 0.978723 (-2925 4600);
PAINT WHITE (-2925 4600);
DISPLAY INVISIBLE (-2925 4600);
FORCEPROP 2 LAST ROOM PVCCIN_CPU1_DECAP_VR
J 0
(-2925 4550);
PAINT ORANGE (-2925 4550);
DISPLAY INVISIBLE (-2925 4550);
FORCEADD CAP_A..1
(-5200 3150);
FORCEPROP 1 LAST LOCATION C2D24
J 0
(-5150 3250);
DISPLAY 0.617021 (-5150 3250);
PAINT AQUA (-5150 3250);
FORCEPROP 1 LAST PART_NUMBER E15431-004
J 0
(-5150 3000);
DISPLAY 0.617021 (-5150 3000);
PAINT BLUE (-5150 3000);
FORCEPROP 1 LAST VALUE 22.0UF
J 0
(-5150 3200);
DISPLAY 0.617021 (-5150 3200);
PAINT SKYBLUE (-5150 3200);
FORCEPROP 1 LAST TOLERANCE 20%
J 0
(-5150 3100);
DISPLAY 0.617021 (-5150 3100);
PAINT SKYBLUE (-5150 3100);
FORCEPROP 1 LAST PACK_TYPE 0603V
J 0
(-5150 2950);
DISPLAY 0.617021 (-5150 2950);
PAINT SKYBLUE (-5150 2950);
FORCEPROP 1 LAST VOLTAGE 4V
J 0
(-5150 3150);
DISPLAY 0.617021 (-5150 3150);
PAINT SKYBLUE (-5150 3150);
FORCEPROP 1 LAST MATERIAL X6S
J 0
(-5150 3050);
DISPLAY 0.617021 (-5150 3050);
PAINT SKYBLUE (-5150 3050);
FORCEPROP 1 LASTPIN (-5200 3250) $PN 1
J 0
(-5190 3230);
DISPLAY 0.617021 (-5190 3230);
PAINT GREEN (-5190 3230);
FORCEPROP 1 LASTPIN (-5200 3050) $PN 2
J 0
(-5190 3030);
DISPLAY 0.617021 (-5190 3030);
PAINT GREEN (-5190 3030);
FORCEPROP 2 LAST CDS_LOCATION C2D24
J 0
(-5150 3250);
DISPLAY 0.617021 (-5150 3250);
PAINT AQUA (-5150 3250);
DISPLAY INVISIBLE (-5150 3250);
FORCEPROP 2 LAST BOM_COST PROC
J 0
(-5200 3150);
PAINT MONO (-5200 3150);
DISPLAY INVISIBLE (-5200 3150);
FORCEPROP 2 LAST CDS_LIB dev_discrete
J 0
(-5200 3150);
PAINT ORANGE (-5200 3150);
DISPLAY INVISIBLE (-5200 3150);
FORCEPROP 2 LAST CDS_SEC 1
J 0
(-5150 3350);
PAINT MONO (-5150 3350);
DISPLAY INVISIBLE (-5150 3350);
FORCEPROP 2 LAST $SEC 1
J 0
(-5150 3350);
PAINT MONO (-5150 3350);
DISPLAY INVISIBLE (-5150 3350);
FORCEPROP 1 LAST PATH I80
J 0
(-5150 3300);
DISPLAY 0.978723 (-5150 3300);
PAINT WHITE (-5150 3300);
DISPLAY INVISIBLE (-5150 3300);
FORCEPROP 2 LAST ROOM PVCCIN_CPU1_DECAP_VR
J 0
(-5150 3250);
PAINT ORANGE (-5150 3250);
DISPLAY INVISIBLE (-5150 3250);
FORCEADD CAP_A..1
(-5225 3775);
FORCEPROP 1 LAST LOCATION C2D25
J 0
(-5175 3875);
DISPLAY 0.617021 (-5175 3875);
PAINT AQUA (-5175 3875);
FORCEPROP 1 LAST PART_NUMBER E15431-004
J 0
(-5175 3625);
DISPLAY 0.617021 (-5175 3625);
PAINT BLUE (-5175 3625);
FORCEPROP 1 LAST VALUE 22.0UF
J 0
(-5175 3825);
DISPLAY 0.617021 (-5175 3825);
PAINT SKYBLUE (-5175 3825);
FORCEPROP 1 LAST TOLERANCE 20%
J 0
(-5175 3725);
DISPLAY 0.617021 (-5175 3725);
PAINT SKYBLUE (-5175 3725);
FORCEPROP 1 LAST PACK_TYPE 0603V
J 0
(-5175 3575);
DISPLAY 0.617021 (-5175 3575);
PAINT SKYBLUE (-5175 3575);
FORCEPROP 1 LAST VOLTAGE 4V
J 0
(-5175 3775);
DISPLAY 0.617021 (-5175 3775);
PAINT SKYBLUE (-5175 3775);
FORCEPROP 1 LAST MATERIAL X6S
J 0
(-5175 3675);
DISPLAY 0.617021 (-5175 3675);
PAINT SKYBLUE (-5175 3675);
FORCEPROP 1 LASTPIN (-5225 3875) $PN 1
J 0
(-5215 3855);
DISPLAY 0.617021 (-5215 3855);
PAINT GREEN (-5215 3855);
FORCEPROP 1 LASTPIN (-5225 3675) $PN 2
J 0
(-5215 3655);
DISPLAY 0.617021 (-5215 3655);
PAINT GREEN (-5215 3655);
FORCEPROP 2 LAST CDS_LOCATION C2D25
J 0
(-5175 3875);
DISPLAY 0.617021 (-5175 3875);
PAINT AQUA (-5175 3875);
DISPLAY INVISIBLE (-5175 3875);
FORCEPROP 2 LAST BOM_COST PROC
J 0
(-5225 3775);
PAINT MONO (-5225 3775);
DISPLAY INVISIBLE (-5225 3775);
FORCEPROP 2 LAST CDS_LIB dev_discrete
J 0
(-5225 3775);
PAINT ORANGE (-5225 3775);
DISPLAY INVISIBLE (-5225 3775);
FORCEPROP 2 LAST CDS_SEC 1
J 0
(-5175 3975);
PAINT MONO (-5175 3975);
DISPLAY INVISIBLE (-5175 3975);
FORCEPROP 2 LAST $SEC 1
J 0
(-5175 3975);
PAINT MONO (-5175 3975);
DISPLAY INVISIBLE (-5175 3975);
FORCEPROP 1 LAST PATH I82
J 0
(-5175 3925);
DISPLAY 0.978723 (-5175 3925);
PAINT WHITE (-5175 3925);
DISPLAY INVISIBLE (-5175 3925);
FORCEPROP 2 LAST ROOM PVCCIN_CPU1_DECAP_VR
J 0
(-5175 3875);
PAINT ORANGE (-5175 3875);
DISPLAY INVISIBLE (-5175 3875);
FORCEADD CAP_A..1
(-5550 3775);
FORCEPROP 1 LAST LOCATION C2D30
J 0
(-5500 3875);
DISPLAY 0.617021 (-5500 3875);
PAINT AQUA (-5500 3875);
FORCEPROP 1 LAST PART_NUMBER E15431-004
J 0
(-5500 3625);
DISPLAY 0.617021 (-5500 3625);
PAINT BLUE (-5500 3625);
FORCEPROP 1 LAST VALUE 22.0UF
J 0
(-5500 3825);
DISPLAY 0.617021 (-5500 3825);
PAINT SKYBLUE (-5500 3825);
FORCEPROP 1 LAST TOLERANCE 20%
J 0
(-5500 3725);
DISPLAY 0.617021 (-5500 3725);
PAINT SKYBLUE (-5500 3725);
FORCEPROP 1 LAST PACK_TYPE 0603V
J 0
(-5500 3575);
DISPLAY 0.617021 (-5500 3575);
PAINT SKYBLUE (-5500 3575);
FORCEPROP 1 LAST VOLTAGE 4V
J 0
(-5500 3775);
DISPLAY 0.617021 (-5500 3775);
PAINT SKYBLUE (-5500 3775);
FORCEPROP 1 LAST MATERIAL X6S
J 0
(-5500 3675);
DISPLAY 0.617021 (-5500 3675);
PAINT SKYBLUE (-5500 3675);
FORCEPROP 1 LASTPIN (-5550 3875) $PN 1
J 0
(-5540 3855);
DISPLAY 0.617021 (-5540 3855);
PAINT GREEN (-5540 3855);
FORCEPROP 1 LASTPIN (-5550 3675) $PN 2
J 0
(-5540 3655);
DISPLAY 0.617021 (-5540 3655);
PAINT GREEN (-5540 3655);
FORCEPROP 2 LAST CDS_LOCATION C2D30
J 0
(-5500 3875);
DISPLAY 0.617021 (-5500 3875);
PAINT AQUA (-5500 3875);
DISPLAY INVISIBLE (-5500 3875);
FORCEPROP 2 LAST BOM_COST PROC
J 0
(-5550 3775);
PAINT MONO (-5550 3775);
DISPLAY INVISIBLE (-5550 3775);
FORCEPROP 2 LAST CDS_LIB dev_discrete
J 0
(-5550 3775);
PAINT ORANGE (-5550 3775);
DISPLAY INVISIBLE (-5550 3775);
FORCEPROP 2 LAST CDS_SEC 1
J 0
(-5500 3975);
PAINT MONO (-5500 3975);
DISPLAY INVISIBLE (-5500 3975);
FORCEPROP 2 LAST $SEC 1
J 0
(-5500 3975);
PAINT MONO (-5500 3975);
DISPLAY INVISIBLE (-5500 3975);
FORCEPROP 1 LAST PATH I83
J 0
(-5500 3925);
DISPLAY 0.978723 (-5500 3925);
PAINT WHITE (-5500 3925);
DISPLAY INVISIBLE (-5500 3925);
FORCEPROP 2 LAST ROOM PVCCIN_CPU1_DECAP_VR
J 0
(-5500 3875);
PAINT ORANGE (-5500 3875);
DISPLAY INVISIBLE (-5500 3875);
FORCEADD CAP_A..1
(-5875 3775);
FORCEPROP 1 LAST LOCATION C2D33
J 0
(-5825 3875);
DISPLAY 0.617021 (-5825 3875);
PAINT AQUA (-5825 3875);
FORCEPROP 1 LAST PART_NUMBER E15431-004
J 0
(-5825 3625);
DISPLAY 0.617021 (-5825 3625);
PAINT BLUE (-5825 3625);
FORCEPROP 1 LAST VALUE 22.0UF
J 0
(-5825 3825);
DISPLAY 0.617021 (-5825 3825);
PAINT SKYBLUE (-5825 3825);
FORCEPROP 1 LAST TOLERANCE 20%
J 0
(-5825 3725);
DISPLAY 0.617021 (-5825 3725);
PAINT SKYBLUE (-5825 3725);
FORCEPROP 1 LAST PACK_TYPE 0603V
J 0
(-5825 3575);
DISPLAY 0.617021 (-5825 3575);
PAINT SKYBLUE (-5825 3575);
FORCEPROP 1 LAST VOLTAGE 4V
J 0
(-5825 3775);
DISPLAY 0.617021 (-5825 3775);
PAINT SKYBLUE (-5825 3775);
FORCEPROP 1 LAST MATERIAL X6S
J 0
(-5825 3675);
DISPLAY 0.617021 (-5825 3675);
PAINT SKYBLUE (-5825 3675);
FORCEPROP 1 LASTPIN (-5875 3875) $PN 1
J 0
(-5865 3855);
DISPLAY 0.617021 (-5865 3855);
PAINT GREEN (-5865 3855);
FORCEPROP 1 LASTPIN (-5875 3675) $PN 2
J 0
(-5865 3655);
DISPLAY 0.617021 (-5865 3655);
PAINT GREEN (-5865 3655);
FORCEPROP 2 LAST CDS_LOCATION C2D33
J 0
(-5825 3875);
DISPLAY 0.617021 (-5825 3875);
PAINT AQUA (-5825 3875);
DISPLAY INVISIBLE (-5825 3875);
FORCEPROP 2 LAST BOM_COST PROC
J 0
(-5875 3775);
PAINT MONO (-5875 3775);
DISPLAY INVISIBLE (-5875 3775);
FORCEPROP 2 LAST CDS_LIB dev_discrete
J 0
(-5875 3775);
PAINT ORANGE (-5875 3775);
DISPLAY INVISIBLE (-5875 3775);
FORCEPROP 2 LAST CDS_SEC 1
J 0
(-5825 3975);
PAINT MONO (-5825 3975);
DISPLAY INVISIBLE (-5825 3975);
FORCEPROP 2 LAST $SEC 1
J 0
(-5825 3975);
PAINT MONO (-5825 3975);
DISPLAY INVISIBLE (-5825 3975);
FORCEPROP 1 LAST PATH I85
J 0
(-5825 3925);
DISPLAY 0.978723 (-5825 3925);
PAINT WHITE (-5825 3925);
DISPLAY INVISIBLE (-5825 3925);
FORCEPROP 2 LAST ROOM PVCCIN_CPU1_DECAP_VR
J 0
(-5825 3875);
PAINT ORANGE (-5825 3875);
DISPLAY INVISIBLE (-5825 3875);
FORCEADD CAP..1
(-5425 2200);
FORCEPROP 1 LAST LOCATION C8P4
J 0
(-5375 2300);
DISPLAY 0.617021 (-5375 2300);
PAINT AQUA (-5375 2300);
FORCEPROP 1 LAST PART_NUMBER C95333-006
R 1
J 0
(-5475 2025);
DISPLAY 0.617021 (-5475 2025);
PAINT BLUE (-5475 2025);
FORCEPROP 1 LAST VALUE 47UF
J 0
(-5375 2250);
DISPLAY 0.617021 (-5375 2250);
PAINT SKYBLUE (-5375 2250);
FORCEPROP 1 LAST TOLERANCE 20%
J 0
(-5375 2150);
DISPLAY 0.617021 (-5375 2150);
PAINT SKYBLUE (-5375 2150);
FORCEPROP 1 LAST PACK_TYPE 0805
J 0
(-5375 2050);
DISPLAY 0.617021 (-5375 2050);
PAINT SKYBLUE (-5375 2050);
FORCEPROP 1 LASTPIN (-5425 2100) $PN 2
J 0
(-5415 2080);
DISPLAY 0.617021 (-5415 2080);
PAINT GREEN (-5415 2080);
FORCEPROP 1 LASTPIN (-5425 2300) $PN 1
J 0
(-5415 2280);
DISPLAY 0.617021 (-5415 2280);
PAINT GREEN (-5415 2280);
FORCEPROP 1 LAST VOLTAGE 4V
J 0
(-5375 2200);
PAINT SKYBLUE (-5375 2200);
DISPLAY INVISIBLE (-5375 2200);
FORCEPROP 1 LAST MATERIAL X6S
J 0
(-5375 2100);
PAINT SKYBLUE (-5375 2100);
DISPLAY INVISIBLE (-5375 2100);
FORCEPROP 2 LAST CDS_LIB mstr_discrete
J 0
(-5425 2200);
PAINT ORANGE (-5425 2200);
DISPLAY INVISIBLE (-5425 2200);
FORCEPROP 2 LAST BOM_COST PROC
J 0
(-5425 2200);
PAINT MONO (-5425 2200);
DISPLAY INVISIBLE (-5425 2200);
FORCEPROP 2 LAST CDS_SEC 1
J 0
(-5375 2400);
DISPLAY 1.021277 (-5375 2400);
PAINT ORANGE (-5375 2400);
DISPLAY INVISIBLE (-5375 2400);
FORCEPROP 2 LAST $SEC 1
J 0
(-5375 2400);
DISPLAY 0.680851 (-5375 2400);
PAINT MONO (-5375 2400);
DISPLAY INVISIBLE (-5375 2400);
FORCEPROP 2 LAST CDS_LOCATION C8P4
J 0
(-5375 2300);
DISPLAY 0.617021 (-5375 2300);
PAINT AQUA (-5375 2300);
DISPLAY INVISIBLE (-5375 2300);
FORCEPROP 1 LAST PATH I88
J 0
(-5375 2350);
DISPLAY 0.978723 (-5375 2350);
PAINT WHITE (-5375 2350);
DISPLAY INVISIBLE (-5375 2350);
FORCEPROP 2 LAST ROOM PVCCIN_CPU1_DECAP_VR
J 0
(-5375 2300);
PAINT ORANGE (-5375 2300);
DISPLAY INVISIBLE (-5375 2300);
FORCEADD CAP..1
(-5700 2200);
FORCEPROP 1 LAST LOCATION C8P20
J 0
(-5650 2300);
DISPLAY 0.617021 (-5650 2300);
PAINT AQUA (-5650 2300);
FORCEPROP 1 LAST PART_NUMBER C95333-006
R 1
J 0
(-5750 2025);
DISPLAY 0.617021 (-5750 2025);
PAINT BLUE (-5750 2025);
FORCEPROP 1 LAST VALUE 47UF
J 0
(-5650 2250);
DISPLAY 0.617021 (-5650 2250);
PAINT SKYBLUE (-5650 2250);
FORCEPROP 1 LAST TOLERANCE 20%
J 0
(-5650 2150);
DISPLAY 0.617021 (-5650 2150);
PAINT SKYBLUE (-5650 2150);
FORCEPROP 1 LAST PACK_TYPE 0805
J 0
(-5650 2050);
DISPLAY 0.617021 (-5650 2050);
PAINT SKYBLUE (-5650 2050);
FORCEPROP 1 LASTPIN (-5700 2100) $PN 2
J 0
(-5690 2080);
DISPLAY 0.617021 (-5690 2080);
PAINT GREEN (-5690 2080);
FORCEPROP 1 LASTPIN (-5700 2300) $PN 1
J 0
(-5690 2280);
DISPLAY 0.617021 (-5690 2280);
PAINT GREEN (-5690 2280);
FORCEPROP 1 LAST VOLTAGE 4V
J 0
(-5650 2200);
PAINT SKYBLUE (-5650 2200);
DISPLAY INVISIBLE (-5650 2200);
FORCEPROP 1 LAST MATERIAL X6S
J 0
(-5650 2100);
PAINT SKYBLUE (-5650 2100);
DISPLAY INVISIBLE (-5650 2100);
FORCEPROP 2 LAST CDS_LIB mstr_discrete
J 0
(-5700 2200);
PAINT ORANGE (-5700 2200);
DISPLAY INVISIBLE (-5700 2200);
FORCEPROP 2 LAST BOM_COST PROC
J 0
(-5700 2200);
PAINT MONO (-5700 2200);
DISPLAY INVISIBLE (-5700 2200);
FORCEPROP 2 LAST CDS_SEC 1
J 0
(-5650 2400);
DISPLAY 1.021277 (-5650 2400);
PAINT ORANGE (-5650 2400);
DISPLAY INVISIBLE (-5650 2400);
FORCEPROP 2 LAST $SEC 1
J 0
(-5650 2400);
DISPLAY 0.680851 (-5650 2400);
PAINT MONO (-5650 2400);
DISPLAY INVISIBLE (-5650 2400);
FORCEPROP 2 LAST CDS_LOCATION C8P20
J 0
(-5650 2300);
DISPLAY 0.617021 (-5650 2300);
PAINT AQUA (-5650 2300);
DISPLAY INVISIBLE (-5650 2300);
FORCEPROP 1 LAST PATH I89
J 0
(-5650 2350);
DISPLAY 0.978723 (-5650 2350);
PAINT WHITE (-5650 2350);
DISPLAY INVISIBLE (-5650 2350);
FORCEPROP 2 LAST ROOM PVCCIN_CPU1_DECAP_VR
J 0
(-5625 2300);
PAINT ORANGE (-5625 2300);
DISPLAY INVISIBLE (-5625 2300);
FORCEADD CAP_A..1
(-5850 3150);
FORCEPROP 1 LAST LOCATION C2D32
J 0
(-5800 3250);
DISPLAY 0.617021 (-5800 3250);
PAINT AQUA (-5800 3250);
FORCEPROP 1 LAST PART_NUMBER E15431-004
J 0
(-5800 3000);
DISPLAY 0.617021 (-5800 3000);
PAINT BLUE (-5800 3000);
FORCEPROP 1 LAST VALUE 22.0UF
J 0
(-5800 3200);
DISPLAY 0.617021 (-5800 3200);
PAINT SKYBLUE (-5800 3200);
FORCEPROP 1 LAST TOLERANCE 20%
J 0
(-5800 3100);
DISPLAY 0.617021 (-5800 3100);
PAINT SKYBLUE (-5800 3100);
FORCEPROP 1 LAST PACK_TYPE 0603V
J 0
(-5800 2950);
DISPLAY 0.617021 (-5800 2950);
PAINT SKYBLUE (-5800 2950);
FORCEPROP 1 LAST VOLTAGE 4V
J 0
(-5800 3150);
DISPLAY 0.617021 (-5800 3150);
PAINT SKYBLUE (-5800 3150);
FORCEPROP 1 LAST MATERIAL X6S
J 0
(-5800 3050);
DISPLAY 0.617021 (-5800 3050);
PAINT SKYBLUE (-5800 3050);
FORCEPROP 1 LASTPIN (-5850 3250) $PN 1
J 0
(-5840 3230);
DISPLAY 0.617021 (-5840 3230);
PAINT GREEN (-5840 3230);
FORCEPROP 1 LASTPIN (-5850 3050) $PN 2
J 0
(-5840 3030);
DISPLAY 0.617021 (-5840 3030);
PAINT GREEN (-5840 3030);
FORCEPROP 2 LAST CDS_LOCATION C2D32
J 0
(-5800 3250);
DISPLAY 0.617021 (-5800 3250);
PAINT AQUA (-5800 3250);
DISPLAY INVISIBLE (-5800 3250);
FORCEPROP 2 LAST BOM_COST PROC
J 0
(-5850 3150);
PAINT MONO (-5850 3150);
DISPLAY INVISIBLE (-5850 3150);
FORCEPROP 2 LAST CDS_LIB dev_discrete
J 0
(-5850 3150);
PAINT ORANGE (-5850 3150);
DISPLAY INVISIBLE (-5850 3150);
FORCEPROP 2 LAST CDS_SEC 1
J 0
(-5800 3350);
PAINT MONO (-5800 3350);
DISPLAY INVISIBLE (-5800 3350);
FORCEPROP 2 LAST $SEC 1
J 0
(-5800 3350);
PAINT MONO (-5800 3350);
DISPLAY INVISIBLE (-5800 3350);
FORCEPROP 1 LAST PATH I90
J 0
(-5800 3300);
DISPLAY 0.978723 (-5800 3300);
PAINT WHITE (-5800 3300);
DISPLAY INVISIBLE (-5800 3300);
FORCEPROP 2 LAST ROOM PVCCIN_CPU1_DECAP_VR
J 0
(-5800 3250);
PAINT ORANGE (-5800 3250);
DISPLAY INVISIBLE (-5800 3250);
FORCEADD CAP..1
(-5975 2200);
FORCEPROP 1 LAST LOCATION C8P18
J 0
(-5925 2300);
DISPLAY 0.617021 (-5925 2300);
PAINT AQUA (-5925 2300);
FORCEPROP 1 LAST PART_NUMBER C95333-006
R 1
J 0
(-6025 2025);
DISPLAY 0.617021 (-6025 2025);
PAINT BLUE (-6025 2025);
FORCEPROP 1 LAST VALUE 47UF
J 0
(-5925 2250);
DISPLAY 0.617021 (-5925 2250);
PAINT SKYBLUE (-5925 2250);
FORCEPROP 1 LAST TOLERANCE 20%
J 0
(-5925 2150);
DISPLAY 0.617021 (-5925 2150);
PAINT SKYBLUE (-5925 2150);
FORCEPROP 1 LAST PACK_TYPE 0805
J 0
(-5925 2050);
DISPLAY 0.617021 (-5925 2050);
PAINT SKYBLUE (-5925 2050);
FORCEPROP 1 LASTPIN (-5975 2100) $PN 2
J 0
(-5965 2080);
DISPLAY 0.617021 (-5965 2080);
PAINT GREEN (-5965 2080);
FORCEPROP 1 LASTPIN (-5975 2300) $PN 1
J 0
(-5965 2280);
DISPLAY 0.617021 (-5965 2280);
PAINT GREEN (-5965 2280);
FORCEPROP 1 LAST VOLTAGE 4V
J 0
(-5925 2200);
PAINT SKYBLUE (-5925 2200);
DISPLAY INVISIBLE (-5925 2200);
FORCEPROP 1 LAST MATERIAL X6S
J 0
(-5925 2100);
PAINT SKYBLUE (-5925 2100);
DISPLAY INVISIBLE (-5925 2100);
FORCEPROP 2 LAST BOM_COST PROC
J 0
(-5975 2200);
PAINT MONO (-5975 2200);
DISPLAY INVISIBLE (-5975 2200);
FORCEPROP 2 LAST CDS_LIB mstr_discrete
J 0
(-5975 2200);
PAINT ORANGE (-5975 2200);
DISPLAY INVISIBLE (-5975 2200);
FORCEPROP 2 LAST CDS_SEC 1
J 0
(-5925 2400);
DISPLAY 1.021277 (-5925 2400);
PAINT ORANGE (-5925 2400);
DISPLAY INVISIBLE (-5925 2400);
FORCEPROP 2 LAST $SEC 1
J 0
(-5925 2400);
DISPLAY 0.680851 (-5925 2400);
PAINT MONO (-5925 2400);
DISPLAY INVISIBLE (-5925 2400);
FORCEPROP 2 LAST CDS_LOCATION C8P18
J 0
(-5925 2300);
DISPLAY 0.617021 (-5925 2300);
PAINT AQUA (-5925 2300);
DISPLAY INVISIBLE (-5925 2300);
FORCEPROP 1 LAST PATH I92
J 0
(-5925 2350);
DISPLAY 0.978723 (-5925 2350);
PAINT WHITE (-5925 2350);
DISPLAY INVISIBLE (-5925 2350);
FORCEPROP 2 LAST ROOM PVCCIN_CPU1_DECAP_VR
J 0
(-5925 2300);
PAINT ORANGE (-5925 2300);
DISPLAY INVISIBLE (-5925 2300);
FORCEADD GND..1
(-5150 1825);
FORCEPROP 3 LASTPIN (-5150 1875) SIG_NAME GND\g
J 0
(-5140 1885);
DISPLAY 0.659574 (-5140 1885);
PAINT MONO (-5140 1885);
DISPLAY INVISIBLE (-5140 1885);
FORCEPROP 1 LAST VOLTAGE 0
J 0
(-5150 1825);
PAINT SKYBLUE (-5150 1825);
DISPLAY INVISIBLE (-5150 1825);
FORCEPROP 1 LAST SIZE 1B
J 0
(-5075 1775);
DISPLAY 0.893617 (-5075 1775);
PAINT GREEN (-5075 1775);
DISPLAY INVISIBLE (-5075 1775);
FORCEPROP 2 LAST CDS_LIB mstr_symbols
J 0
(-5150 1825);
PAINT ORANGE (-5150 1825);
DISPLAY INVISIBLE (-5150 1825);
FORCEPROP 1 LAST BODY_TYPE PLUMBING
J 0
(-5195 1782);
DISPLAY 0.340426 (-5195 1782);
PAINT GREEN (-5195 1782);
DISPLAY INVISIBLE (-5195 1782);
FORCEPROP 1 LAST PATH I93
J 0
(-5075 1825);
DISPLAY 0.872340 (-5075 1825);
PAINT AQUA (-5075 1825);
DISPLAY INVISIBLE (-5075 1825);
FORCEPROP 2 LAST ROOM PVCCIN_CPU1_DECAP_VR
J 0
(-5700 1900);
PAINT ORANGE (-5700 1900);
DISPLAY INVISIBLE (-5700 1900);
FORCEPROP 1 LAST HDL_POWER GND
J 0
(-5150 1975);
DISPLAY 0.893617 (-5150 1975);
PAINT GREEN (-5150 1975);
DISPLAY INVISIBLE (-5150 1975);
FORCEADD GND..1
(-5300 1225);
FORCEPROP 3 LASTPIN (-5300 1275) SIG_NAME GND\g
J 0
(-5290 1285);
DISPLAY 0.659574 (-5290 1285);
PAINT MONO (-5290 1285);
DISPLAY INVISIBLE (-5290 1285);
FORCEPROP 1 LAST VOLTAGE 0
J 0
(-5300 1225);
PAINT SKYBLUE (-5300 1225);
DISPLAY INVISIBLE (-5300 1225);
FORCEPROP 2 LAST CDS_LIB mstr_symbols
J 0
(-5300 1225);
PAINT ORANGE (-5300 1225);
DISPLAY INVISIBLE (-5300 1225);
FORCEPROP 1 LAST SIZE 1B
J 0
(-5225 1175);
DISPLAY 0.893617 (-5225 1175);
PAINT GREEN (-5225 1175);
DISPLAY INVISIBLE (-5225 1175);
FORCEPROP 1 LAST BODY_TYPE PLUMBING
J 0
(-5345 1182);
DISPLAY 0.340426 (-5345 1182);
PAINT GREEN (-5345 1182);
DISPLAY INVISIBLE (-5345 1182);
FORCEPROP 1 LAST PATH I95
J 0
(-5225 1225);
DISPLAY 0.872340 (-5225 1225);
PAINT AQUA (-5225 1225);
DISPLAY INVISIBLE (-5225 1225);
FORCEPROP 2 LAST ROOM PVCCIN_CPU1_DECAP_VR
J 0
(-5850 1300);
PAINT ORANGE (-5850 1300);
DISPLAY INVISIBLE (-5850 1300);
FORCEPROP 1 LAST HDL_POWER GND
J 0
(-5300 1375);
DISPLAY 0.893617 (-5300 1375);
PAINT GREEN (-5300 1375);
DISPLAY INVISIBLE (-5300 1375);
FORCEADD GND..1
(-5275 575);
FORCEPROP 3 LASTPIN (-5275 625) SIG_NAME GND\g
J 0
(-5265 635);
DISPLAY 0.659574 (-5265 635);
PAINT MONO (-5265 635);
DISPLAY INVISIBLE (-5265 635);
FORCEPROP 1 LAST VOLTAGE 0
J 0
(-5275 575);
PAINT SKYBLUE (-5275 575);
DISPLAY INVISIBLE (-5275 575);
FORCEPROP 1 LAST SIZE 1B
J 0
(-5200 525);
DISPLAY 0.893617 (-5200 525);
PAINT GREEN (-5200 525);
DISPLAY INVISIBLE (-5200 525);
FORCEPROP 2 LAST CDS_LIB mstr_symbols
J 0
(-5275 575);
PAINT ORANGE (-5275 575);
DISPLAY INVISIBLE (-5275 575);
FORCEPROP 1 LAST BODY_TYPE PLUMBING
J 0
(-5320 532);
DISPLAY 0.340426 (-5320 532);
PAINT GREEN (-5320 532);
DISPLAY INVISIBLE (-5320 532);
FORCEPROP 1 LAST PATH I97
J 0
(-5200 575);
DISPLAY 0.872340 (-5200 575);
PAINT AQUA (-5200 575);
DISPLAY INVISIBLE (-5200 575);
FORCEPROP 2 LAST ROOM PVCCIN_CPU1_DECAP_VR
J 0
(-5825 650);
PAINT ORANGE (-5825 650);
DISPLAY INVISIBLE (-5825 650);
FORCEPROP 1 LAST HDL_POWER GND
J 0
(-5275 725);
DISPLAY 0.893617 (-5275 725);
PAINT GREEN (-5275 725);
DISPLAY INVISIBLE (-5275 725);
FORCEADD DESIGN_NOTE..1
(-1025 3150);
PAINT PURPLE (-1025 3150);
FORCEPROP 0 LAST L2 CAPACITORS.
J 0
(-1225 2975);
PAINT VIOLET (-1225 2975);
FORCEPROP 0 LAST L1 * HIGH TEMPERATURE
J 0
(-1225 3025);
PAINT VIOLET (-1225 3025);
FORCEPROP 0 LAST L4 SKT 0 CAVITY (TOP)
J 0
(-1225 2850);
PAINT VIOLET (-1225 2850);
FORCEPROP 0 LAST L3 * TO BE PLACED IN
J 0
(-1225 2900);
PAINT VIOLET (-1225 2900);
FORCEPROP 2 LAST CDS_LIB mstr_symbols
J 0
(-1025 3150);
PAINT MONO (-1025 3150);
DISPLAY INVISIBLE (-1025 3150);
FORCEPROP 2 LAST BOM_COST SM_CONTROLLER
J 0
(-1225 3100);
PAINT MONO (-1225 3100);
DISPLAY INVISIBLE (-1225 3100);
FORCEPROP 1 LAST COMMENT_BODY TRUE
J 0
(-1000 3250);
DISPLAY 1.319149 (-1000 3250);
PAINT GREEN (-1000 3250);
DISPLAY INVISIBLE (-1000 3250);
FORCEPROP 2 LAST ROOM PVCCIN_CPU1_DECAP_VR
J 0
(-1225 3100);
PAINT MONO (-1225 3100);
DISPLAY INVISIBLE (-1225 3100);
FORCEADD DESIGN_NOTE..1
(-1050 1000);
PAINT PURPLE (-1050 1000);
FORCEPROP 0 LAST L3 * TO BE PLACED IN
J 0
(-1250 750);
PAINT VIOLET (-1250 750);
FORCEPROP 0 LAST L4 SKT 0 CAVITY (BOTTOM)
J 0
(-1250 700);
PAINT VIOLET (-1250 700);
FORCEPROP 0 LAST L2 CAPACITORS.
J 0
(-1250 825);
PAINT VIOLET (-1250 825);
FORCEPROP 0 LAST L1 * HIGH TEMPERATURE
J 0
(-1250 875);
PAINT VIOLET (-1250 875);
FORCEPROP 2 LAST CDS_LIB mstr_symbols
J 0
(-1050 1000);
PAINT MONO (-1050 1000);
DISPLAY INVISIBLE (-1050 1000);
FORCEPROP 2 LAST BOM_COST SM_CONTROLLER
J 0
(-1250 950);
PAINT MONO (-1250 950);
DISPLAY INVISIBLE (-1250 950);
FORCEPROP 1 LAST COMMENT_BODY TRUE
J 0
(-1025 1100);
DISPLAY 1.319149 (-1025 1100);
PAINT GREEN (-1025 1100);
DISPLAY INVISIBLE (-1025 1100);
FORCEPROP 2 LAST ROOM PVCCIN_CPU1_DECAP_VR
J 0
(-1250 950);
PAINT MONO (-1250 950);
DISPLAY INVISIBLE (-1250 950);
FORCEADD INTEL_CORP_BPAGE..1
(0 0);
FORCEPROP 1 LAST CDS_CON_LAST_MODIFIED Tue Dec 01 11:51:40 2015
J 0
(-1425 325);
PAINT ORANGE (-1425 325);
DISPLAY INVISIBLE (-1425 325);
FORCEPROP 1 LAST CUSTOM_TXT_CDS <CURRENT_DESIGN_SHEET> OF <TOTAL_DESIGN_SHEETS>
J 0
(-500 25);
PAINT GREEN (-500 25);
FORCEPROP 1 LAST CUSTOM_TXT_CDS <CON_LAST_MODIFIED>
J 0
(-1925 350);
PAINT GREEN (-1925 350);
FORCEPROP 2 LAST CUSTOM_TXT_CDS <XR_PAGE_TITLE>
J 0
(-7890 5250);
DISPLAY 0.638298 (-7890 5250);
PAINT PINK (-7890 5250);
DISPLAY INVISIBLE (-7890 5250);
FORCEPROP 1 LAST SCH_ADDRESS3 Santa Clara, CA 95052-8119
J 0
(-3975 25);
DISPLAY 0.617021 (-3975 25);
PAINT GREEN (-3975 25);
FORCEPROP 1 LAST SCH_ADDRESS2 P.O. BOX 58119
J 0
(-3975 75);
DISPLAY 0.617021 (-3975 75);
PAINT GREEN (-3975 75);
FORCEPROP 1 LAST SCH_ADDRESS1 2200 Mission College Blvd.
J 0
(-3975 125);
DISPLAY 0.617021 (-3975 125);
PAINT GREEN (-3975 125);
FORCEPROP 1 LAST SCH_TITLE CPU1 DECOUPLING CAVITY CAPS
J 0
(-7950 50);
DISPLAY 1.212766 (-7950 50);
PAINT ORANGE (-7950 50);
FORCEPROP 1 LAST SCH_NUMBER H4694802
J 0
(-1300 150);
DISPLAY 1.212766 (-1300 150);
PAINT YELLOW (-1300 150);
FORCEPROP 1 LAST SCH_DEPT BESD
J 1
(-4450 100);
DISPLAY 1.212766 (-4450 100);
PAINT YELLOW (-4450 100);
FORCEPROP 1 LAST SCH_REV 2.420
J 0
(-250 150);
DISPLAY 0.978723 (-250 150);
PAINT YELLOW (-250 150);
FORCEPROP 2 LAST PAGE_BORDER TRUE
J 0
(-7890 5250);
DISPLAY 0.638298 (-7890 5250);
PAINT PINK (-7890 5250);
DISPLAY INVISIBLE (-7890 5250);
FORCEPROP 2 LAST CDS_LIB mstr_symbols
J 0
(0 0);
PAINT MONO (0 0);
DISPLAY INVISIBLE (0 0);
FORCEPROP 1 LAST COMMENT_BODY TRUE
J 0
(12 12);
DISPLAY 0.468085 (12 12);
PAINT GREEN (12 12);
DISPLAY INVISIBLE (12 12);
FORCEPROP 2 LAST CDS_XR_PAGE_TITLE CR-76 : @BASEBOARD_FAB2_LIB.BASEBOARD_FAB2(SCH_1):PAGE76
J 0
(-7890 5250);
DISPLAY 0.638298 (-7890 5250);
PAINT PINK (-7890 5250);
DISPLAY INVISIBLE (-7890 5250);
WIRE 16 -1 (-7675 3675)(-7675 3575);
WIRE 16 -1 (-7675 3575)(-7325 3575);
WIRE 16 -1 (-7325 3675)(-7325 3575);
WIRE 16 -1 (-7325 3575)(-7000 3575);
WIRE 16 -1 (-7000 3675)(-7000 3575);
WIRE 16 -1 (-7000 3575)(-6650 3575);
WIRE 16 -1 (-6650 3675)(-6650 3575);
WIRE 16 -1 (-6650 3575)(-6300 3575);
WIRE 16 -1 (-6300 3675)(-6300 3575);
WIRE 16 -1 (-6300 3500)(-6300 3575);
WIRE 16 -1 (-7625 3050)(-7625 2950);
WIRE 16 -1 (-7625 2950)(-7275 2950);
WIRE 16 -1 (-7275 3050)(-7275 2950);
WIRE 16 -1 (-7275 2950)(-6950 2950);
WIRE 16 -1 (-6950 3050)(-6950 2950);
WIRE 16 -1 (-6950 2950)(-6600 2950);
WIRE 16 -1 (-6600 3025)(-6600 2950);
WIRE 16 -1 (-6600 2950)(-6250 2950);
WIRE 16 -1 (-6250 3050)(-6250 2950);
WIRE 16 -1 (-6250 2875)(-6250 2950);
WIRE 16 -1 (-7725 2100)(-7725 2000);
WIRE 16 -1 (-7725 2000)(-7375 2000);
WIRE 16 -1 (-7375 2100)(-7375 2000);
WIRE 16 -1 (-7375 2000)(-7050 2000);
WIRE 16 -1 (-7050 2100)(-7050 2000);
WIRE 16 -1 (-7050 2000)(-6700 2000);
WIRE 16 -1 (-6700 2100)(-6700 2000);
WIRE 16 -1 (-6700 2000)(-6350 2000);
WIRE 16 -1 (-6350 2100)(-6350 2000);
WIRE 16 -1 (-6350 1925)(-6350 2000);
WIRE 16 -1 (-7725 1450)(-7725 1350);
WIRE 16 -1 (-7725 1350)(-7375 1350);
WIRE 16 -1 (-7375 1450)(-7375 1350);
WIRE 16 -1 (-7375 1350)(-7050 1350);
WIRE 16 -1 (-7050 1450)(-7050 1350);
WIRE 16 -1 (-7050 1350)(-6700 1350);
WIRE 16 -1 (-6700 1450)(-6700 1350);
WIRE 16 -1 (-6700 1350)(-6350 1350);
WIRE 16 -1 (-6350 1450)(-6350 1350);
WIRE 16 -1 (-6350 1275)(-6350 1350);
WIRE 16 -1 (-7725 800)(-7725 700);
WIRE 16 -1 (-7725 700)(-7375 700);
WIRE 16 -1 (-7375 800)(-7375 700);
WIRE 16 -1 (-7375 700)(-7050 700);
WIRE 16 -1 (-7050 800)(-7050 700);
WIRE 16 -1 (-7050 700)(-6700 700);
WIRE 16 -1 (-6700 800)(-6700 700);
WIRE 16 -1 (-6700 700)(-6350 700);
WIRE 16 -1 (-6350 800)(-6350 700);
WIRE 16 -1 (-6350 625)(-6350 700);
WIRE 16 -1 (-4325 4625)(-4325 4525);
WIRE 16 -1 (-4325 4625)(-4625 4625);
WIRE 16 -1 (-4625 4625)(-4950 4625);
WIRE 16 -1 (-4625 4625)(-4625 4525);
WIRE 16 -1 (-4950 4550)(-4950 4625);
WIRE 16 -1 (-4950 4625)(-5275 4625);
WIRE 16 -1 (-5275 4550)(-5275 4625);
WIRE 16 -1 (-5275 4625)(-5575 4625);
WIRE 16 -1 (-5575 4550)(-5575 4625);
WIRE 16 -1 (-5575 4625)(-5900 4625);
WIRE 16 -1 (-5900 4625)(-5900 4675);
WIRE 16 -1 (-5900 4625)(-5900 4550);
WIRE 16 -1 (-6300 3950)(-6300 3875);
WIRE 16 -1 (-6300 3950)(-6650 3950);
WIRE 16 -1 (-6650 3875)(-6650 3950);
WIRE 16 -1 (-7000 3950)(-6650 3950);
WIRE 16 -1 (-7000 3875)(-7000 3950);
WIRE 16 -1 (-7325 3950)(-7000 3950);
WIRE 16 -1 (-7325 3875)(-7325 3950);
WIRE 16 -1 (-7675 3950)(-7325 3950);
WIRE 16 -1 (-7675 3950)(-7675 4000);
WIRE 16 -1 (-7675 3950)(-7675 3875);
WIRE 16 -1 (-6250 3325)(-6250 3250);
WIRE 16 -1 (-6250 3325)(-6600 3325);
WIRE 16 -1 (-6600 3225)(-6600 3325);
WIRE 16 -1 (-6950 3325)(-6600 3325);
WIRE 16 -1 (-6950 3250)(-6950 3325);
WIRE 16 -1 (-7275 3325)(-6950 3325);
WIRE 16 -1 (-7275 3250)(-7275 3325);
WIRE 16 -1 (-7625 3325)(-7275 3325);
WIRE 16 -1 (-7625 3325)(-7625 3375);
WIRE 16 -1 (-7625 3325)(-7625 3250);
WIRE 16 -1 (-4325 3950)(-4325 3850);
WIRE 16 -1 (-4325 3950)(-4625 3950);
WIRE 16 -1 (-4625 3950)(-4625 3850);
WIRE 16 -1 (-4625 3950)(-4900 3950);
WIRE 16 -1 (-4900 3875)(-4900 3950);
WIRE 16 -1 (-4900 3950)(-5225 3950);
WIRE 16 -1 (-5225 3875)(-5225 3950);
WIRE 16 -1 (-5225 3950)(-5550 3950);
WIRE 16 -1 (-5550 3875)(-5550 3950);
WIRE 16 -1 (-5550 3950)(-5875 3950);
WIRE 16 -1 (-5875 3950)(-5875 4000);
WIRE 16 -1 (-5875 3950)(-5875 3875);
WIRE 16 -1 (-4325 3325)(-4325 3250);
WIRE 16 -1 (-4325 3325)(-4600 3325);
WIRE 16 -1 (-4600 3325)(-4600 3250);
WIRE 16 -1 (-4600 3325)(-4875 3325);
WIRE 16 -1 (-4875 3225)(-4875 3325);
WIRE 16 -1 (-4875 3325)(-5200 3325);
WIRE 16 -1 (-5200 3250)(-5200 3325);
WIRE 16 -1 (-5200 3325)(-5500 3325);
WIRE 16 -1 (-5500 3250)(-5500 3325);
WIRE 16 -1 (-5500 3325)(-5850 3325);
WIRE 16 -1 (-5850 3325)(-5850 3375);
WIRE 16 -1 (-5850 3325)(-5850 3250);
WIRE 16 -1 (-5150 2375)(-5150 2300);
WIRE 16 -1 (-5150 2375)(-5425 2375);
WIRE 16 -1 (-5425 2300)(-5425 2375);
WIRE 16 -1 (-5425 2375)(-5700 2375);
WIRE 16 -1 (-5700 2300)(-5700 2375);
WIRE 16 -1 (-5975 2375)(-5700 2375);
WIRE 16 -1 (-5975 2375)(-5975 2425);
WIRE 16 -1 (-5975 2375)(-5975 2300);
WIRE 16 -1 (-6350 2375)(-6350 2300);
WIRE 16 -1 (-6350 2375)(-6700 2375);
WIRE 16 -1 (-6700 2300)(-6700 2375);
WIRE 16 -1 (-7050 2375)(-6700 2375);
WIRE 16 -1 (-7050 2300)(-7050 2375);
WIRE 16 -1 (-7375 2375)(-7050 2375);
WIRE 16 -1 (-7375 2300)(-7375 2375);
WIRE 16 -1 (-7725 2375)(-7375 2375);
WIRE 16 -1 (-7725 2375)(-7725 2425);
WIRE 16 -1 (-7725 2375)(-7725 2300);
WIRE 16 -1 (-6350 1725)(-6350 1650);
WIRE 16 -1 (-6350 1725)(-6700 1725);
WIRE 16 -1 (-6700 1650)(-6700 1725);
WIRE 16 -1 (-7050 1725)(-6700 1725);
WIRE 16 -1 (-7050 1650)(-7050 1725);
WIRE 16 -1 (-7375 1725)(-7050 1725);
WIRE 16 -1 (-7375 1650)(-7375 1725);
WIRE 16 -1 (-7725 1725)(-7375 1725);
WIRE 16 -1 (-7725 1725)(-7725 1775);
WIRE 16 -1 (-7725 1725)(-7725 1650);
WIRE 16 -1 (-5300 1650)(-5300 1725);
WIRE 16 -1 (-5625 1725)(-5300 1725);
WIRE 16 -1 (-5625 1650)(-5625 1725);
WIRE 16 -1 (-5975 1725)(-5625 1725);
WIRE 16 -1 (-5975 1725)(-5975 1775);
WIRE 16 -1 (-5975 1725)(-5975 1650);
WIRE 16 -1 (-5275 975)(-5275 1050);
WIRE 16 -1 (-5600 1050)(-5275 1050);
WIRE 16 -1 (-5600 975)(-5600 1050);
WIRE 16 -1 (-5950 1050)(-5600 1050);
WIRE 16 -1 (-5950 1050)(-5950 1100);
WIRE 16 -1 (-5950 1050)(-5950 975);
WIRE 16 -1 (-6350 1075)(-6700 1075);
WIRE 16 -1 (-6350 1075)(-6350 1000);
WIRE 16 -1 (-6700 1000)(-6700 1075);
WIRE 16 -1 (-7050 1075)(-6700 1075);
WIRE 16 -1 (-7050 1000)(-7050 1075);
WIRE 16 -1 (-7375 1075)(-7050 1075);
WIRE 16 -1 (-7375 1000)(-7375 1075);
WIRE 16 -1 (-7725 1075)(-7375 1075);
WIRE 16 -1 (-7725 1075)(-7725 1125);
WIRE 16 -1 (-7725 1075)(-7725 1000);
WIRE 16 -1 (-3975 3650)(-3975 3550);
WIRE 16 -1 (-3675 3550)(-3975 3550);
WIRE 16 -1 (-3675 3650)(-3675 3550);
WIRE 16 -1 (-3350 3550)(-3675 3550);
WIRE 16 -1 (-3350 3675)(-3350 3550);
WIRE 16 -1 (-3050 3550)(-3350 3550);
WIRE 16 -1 (-3050 3675)(-3050 3550);
WIRE 16 -1 (-2750 3550)(-3050 3550);
WIRE 16 -1 (-2750 3675)(-2750 3550);
WIRE 16 -1 (-2450 3550)(-2750 3550);
WIRE 16 -1 (-2450 3650)(-2450 3550);
WIRE 16 -1 (-2450 3475)(-2450 3550);
WIRE 16 -1 (-725 4550)(-725 4625);
WIRE 16 -1 (-725 4625)(-975 4625);
WIRE 16 -1 (-975 4625)(-975 4550);
WIRE 16 -1 (-975 4625)(-1275 4625);
WIRE 16 -1 (-1275 4625)(-1275 4550);
WIRE 16 -1 (-1275 4625)(-1600 4625);
WIRE 16 -1 (-1600 4550)(-1600 4625);
WIRE 16 -1 (-1600 4625)(-1875 4625);
WIRE 16 -1 (-1875 4550)(-1875 4625);
WIRE 16 -1 (-1875 4625)(-2175 4625);
WIRE 16 -1 (-2175 4550)(-2175 4625);
WIRE 16 -1 (-2175 4625)(-2450 4625);
WIRE 16 -1 (-2450 4625)(-2450 4550);
WIRE 16 -1 (-2450 4625)(-2725 4625);
WIRE 16 -1 (-2725 4550)(-2725 4625);
WIRE 16 -1 (-2725 4625)(-2975 4625);
WIRE 16 -1 (-2975 4625)(-2975 4550);
WIRE 16 -1 (-2975 4625)(-3250 4625);
WIRE 16 -1 (-3250 4525)(-3250 4625);
WIRE 16 -1 (-3250 4625)(-3500 4625);
WIRE 16 -1 (-3500 4550)(-3500 4625);
WIRE 16 -1 (-3500 4625)(-3750 4625);
WIRE 16 -1 (-3750 4550)(-3750 4625);
WIRE 16 -1 (-3750 4625)(-4000 4625);
WIRE 16 -1 (-4000 4625)(-4000 4675);
WIRE 16 -1 (-4000 4625)(-4000 4550);
WIRE 16 -1 (-500 2325)(-500 2200);
WIRE 16 -1 (-700 2325)(-500 2325);
WIRE 16 -1 (-700 2250)(-700 2325);
WIRE 16 -1 (-700 2325)(-975 2325);
WIRE 16 -1 (-975 2250)(-975 2325);
WIRE 16 -1 (-975 2325)(-1225 2325);
WIRE 16 -1 (-1225 2250)(-1225 2325);
WIRE 16 -1 (-1450 2325)(-1225 2325);
WIRE 16 -1 (-1450 2225)(-1450 2325);
WIRE 16 -1 (-1450 2325)(-1750 2325);
WIRE 16 -1 (-1750 2325)(-1750 2225);
WIRE 16 -1 (-1750 2325)(-2025 2325);
WIRE 16 -1 (-2025 2250)(-2025 2325);
WIRE 16 -1 (-2025 2325)(-2325 2325);
WIRE 16 -1 (-2325 2250)(-2325 2325);
WIRE 16 -1 (-2325 2325)(-2625 2325);
WIRE 16 -1 (-2625 2250)(-2625 2325);
WIRE 16 -1 (-2925 2325)(-2625 2325);
WIRE 16 -1 (-2925 2325)(-2925 2250);
WIRE 16 -1 (-3175 2325)(-2925 2325);
WIRE 16 -1 (-3175 2250)(-3175 2325);
WIRE 16 -1 (-3425 2325)(-3175 2325);
WIRE 16 -1 (-3425 2250)(-3425 2325);
WIRE 16 -1 (-3725 2325)(-3425 2325);
WIRE 16 -1 (-3725 2325)(-3725 2250);
WIRE 16 -1 (-3725 2325)(-4000 2325);
WIRE 16 -1 (-4000 2250)(-4000 2325);
WIRE 16 -1 (-4000 2325)(-4275 2325);
WIRE 16 -1 (-4275 2225)(-4275 2325);
WIRE 16 -1 (-4275 2325)(-4525 2325);
WIRE 16 -1 (-4525 2250)(-4525 2325);
WIRE 16 -1 (-4525 2325)(-4775 2325);
WIRE 16 -1 (-4775 2325)(-4775 2425);
WIRE 16 -1 (-4775 2325)(-4775 2250);
WIRE 16 -1 (-2450 3850)(-2450 3925);
WIRE 16 -1 (-2450 3925)(-2750 3925);
WIRE 16 -1 (-2750 3875)(-2750 3925);
WIRE 16 -1 (-2750 3925)(-3050 3925);
WIRE 16 -1 (-3050 3925)(-3050 3875);
WIRE 16 -1 (-3050 3925)(-3350 3925);
WIRE 16 -1 (-3350 3875)(-3350 3925);
WIRE 16 -1 (-3350 3925)(-3675 3925);
WIRE 16 -1 (-3675 3850)(-3675 3925);
WIRE 16 -1 (-3975 3925)(-3675 3925);
WIRE 16 -1 (-3975 3925)(-3975 3850);
WIRE 16 -1 (-3975 3925)(-3975 3975);
WIRE 16 -1 (-4000 4350)(-4000 4250);
WIRE 16 -1 (-4000 4250)(-3750 4250);
WIRE 16 -1 (-3750 4350)(-3750 4250);
WIRE 16 -1 (-3500 4250)(-3750 4250);
WIRE 16 -1 (-3500 4350)(-3500 4250);
WIRE 16 -1 (-3250 4250)(-3500 4250);
WIRE 16 -1 (-3250 4325)(-3250 4250);
WIRE 16 -1 (-2975 4250)(-3250 4250);
WIRE 16 -1 (-2975 4350)(-2975 4250);
WIRE 16 -1 (-2725 4250)(-2975 4250);
WIRE 16 -1 (-2725 4350)(-2725 4250);
WIRE 16 -1 (-2450 4250)(-2725 4250);
WIRE 16 -1 (-2450 4350)(-2450 4250);
WIRE 16 -1 (-2175 4250)(-2450 4250);
WIRE 16 -1 (-2175 4350)(-2175 4250);
WIRE 16 -1 (-1875 4250)(-2175 4250);
WIRE 16 -1 (-1875 4350)(-1875 4250);
WIRE 16 -1 (-1600 4250)(-1875 4250);
WIRE 16 -1 (-1600 4350)(-1600 4250);
WIRE 16 -1 (-1275 4250)(-1600 4250);
WIRE 16 -1 (-1275 4350)(-1275 4250);
WIRE 16 -1 (-975 4250)(-1275 4250);
WIRE 16 -1 (-975 4350)(-975 4250);
WIRE 16 -1 (-725 4250)(-975 4250);
WIRE 16 -1 (-725 4350)(-725 4250);
WIRE 16 -1 (-725 4150)(-725 4250);
WIRE 16 -1 (-725 3800)(-725 3900);
WIRE 16 -1 (-725 3900)(-950 3900);
WIRE 16 -1 (-950 3825)(-950 3900);
WIRE 16 -1 (-1200 3900)(-950 3900);
WIRE 16 -1 (-1200 3825)(-1200 3900);
WIRE 16 -1 (-1200 3900)(-1450 3900);
WIRE 16 -1 (-1450 3825)(-1450 3900);
WIRE 16 -1 (-1450 3900)(-1700 3900);
WIRE 16 -1 (-1700 3825)(-1700 3900);
WIRE 16 -1 (-1700 3900)(-1950 3900);
WIRE 16 -1 (-1950 3925)(-1950 3900);
WIRE 16 -1 (-1950 3900)(-1950 3825);
WIRE 16 -1 (-1950 3625)(-1950 3500);
WIRE 16 -1 (-1950 3500)(-1700 3500);
WIRE 16 -1 (-1700 3625)(-1700 3500);
WIRE 16 -1 (-1700 3500)(-1450 3500);
WIRE 16 -1 (-1450 3625)(-1450 3500);
WIRE 16 -1 (-1450 3500)(-1200 3500);
WIRE 16 -1 (-1200 3625)(-1200 3500);
WIRE 16 -1 (-1200 3500)(-950 3500);
WIRE 16 -1 (-950 3625)(-950 3500);
WIRE 16 -1 (-950 3500)(-725 3500);
WIRE 16 -1 (-725 3600)(-725 3500);
WIRE 16 -1 (-725 3450)(-725 3500);
WIRE 16 -1 (-4775 2050)(-4775 1950);
WIRE 16 -1 (-4775 1950)(-4525 1950);
WIRE 16 -1 (-4525 2050)(-4525 1950);
WIRE 16 -1 (-4275 1950)(-4525 1950);
WIRE 16 -1 (-4275 2025)(-4275 1950);
WIRE 16 -1 (-4000 1950)(-4275 1950);
WIRE 16 -1 (-4000 2050)(-4000 1950);
WIRE 16 -1 (-3725 1950)(-4000 1950);
WIRE 16 -1 (-3725 2050)(-3725 1950);
WIRE 16 -1 (-3425 1950)(-3725 1950);
WIRE 16 -1 (-3425 2050)(-3425 1950);
WIRE 16 -1 (-3175 1950)(-3425 1950);
WIRE 16 -1 (-3175 2050)(-3175 1950);
WIRE 16 -1 (-2925 1950)(-3175 1950);
WIRE 16 -1 (-2925 2050)(-2925 1950);
WIRE 16 -1 (-2925 1950)(-2625 1950);
WIRE 16 -1 (-2625 2050)(-2625 1950);
WIRE 16 -1 (-2325 1950)(-2625 1950);
WIRE 16 -1 (-2325 2050)(-2325 1950);
WIRE 16 -1 (-2025 1950)(-2325 1950);
WIRE 16 -1 (-2025 2050)(-2025 1950);
WIRE 16 -1 (-1750 1950)(-2025 1950);
WIRE 16 -1 (-1750 2025)(-1750 1950);
WIRE 16 -1 (-1450 1950)(-1750 1950);
WIRE 16 -1 (-1450 2025)(-1450 1950);
WIRE 16 -1 (-1225 1950)(-1450 1950);
WIRE 16 -1 (-1225 2050)(-1225 1950);
WIRE 16 -1 (-975 1950)(-1225 1950);
WIRE 16 -1 (-975 2050)(-975 1950);
WIRE 16 -1 (-700 1950)(-975 1950);
WIRE 16 -1 (-700 2050)(-700 1950);
WIRE 16 -1 (-500 1950)(-700 1950);
WIRE 16 -1 (-500 2000)(-500 1950);
WIRE 16 -1 (-500 1775)(-500 1950);
WIRE 16 -1 (-3300 825)(-3300 725);
WIRE 16 -1 (-3300 725)(-2950 725);
WIRE 16 -1 (-2950 825)(-2950 725);
WIRE 16 -1 (-2950 725)(-2625 725);
WIRE 16 -1 (-2625 825)(-2625 725);
WIRE 16 -1 (-2375 725)(-2625 725);
WIRE 16 -1 (-2375 825)(-2375 725);
WIRE 16 -1 (-2100 725)(-2375 725);
WIRE 16 -1 (-2100 825)(-2100 725);
WIRE 16 -1 (-2100 650)(-2100 725);
WIRE 16 -1 (-3925 2950)(-3925 2850);
WIRE 16 -1 (-3925 2850)(-3525 2850);
WIRE 16 -1 (-3525 2975)(-3525 2850);
WIRE 16 -1 (-3150 2850)(-3525 2850);
WIRE 16 -1 (-3150 2950)(-3150 2850);
WIRE 16 -1 (-2750 2850)(-3150 2850);
WIRE 16 -1 (-2750 2850)(-2750 2950);
WIRE 16 -1 (-2750 2800)(-2750 2850);
WIRE 16 -1 (-2750 3250)(-2750 3150);
WIRE 16 -1 (-2750 3250)(-3150 3250);
WIRE 16 -1 (-3150 3150)(-3150 3250);
WIRE 16 -1 (-3150 3250)(-3525 3250);
WIRE 16 -1 (-3525 3175)(-3525 3250);
WIRE 16 -1 (-3925 3250)(-3525 3250);
WIRE 16 -1 (-3925 3150)(-3925 3250);
WIRE 16 -1 (-3925 3250)(-3925 3275);
WIRE 16 -1 (-2100 1100)(-2100 1025);
WIRE 16 -1 (-2375 1100)(-2100 1100);
WIRE 16 -1 (-2375 1025)(-2375 1100);
WIRE 16 -1 (-2375 1100)(-2625 1100);
WIRE 16 -1 (-2625 1025)(-2625 1100);
WIRE 16 -1 (-2950 1100)(-2625 1100);
WIRE 16 -1 (-2950 1025)(-2950 1100);
WIRE 16 -1 (-3300 1100)(-2950 1100);
WIRE 16 -1 (-3300 1100)(-3300 1025);
WIRE 16 -1 (-3300 1100)(-3300 1150);
WIRE 16 -1 (-4475 850)(-4475 750);
WIRE 16 -1 (-4475 750)(-4125 750);
WIRE 16 -1 (-4125 850)(-4125 750);
WIRE 16 -1 (-4125 750)(-3800 750);
WIRE 16 -1 (-3800 850)(-3800 750);
WIRE 16 -1 (-3800 675)(-3800 750);
WIRE 16 -1 (-3800 1050)(-3800 1125);
WIRE 16 -1 (-4125 1125)(-3800 1125);
WIRE 16 -1 (-4125 1050)(-4125 1125);
WIRE 16 -1 (-4475 1125)(-4125 1125);
WIRE 16 -1 (-4475 1125)(-4475 1175);
WIRE 16 -1 (-4475 1125)(-4475 1050);
WIRE 16 -1 (-5900 4350)(-5900 4250);
WIRE 16 -1 (-5900 4250)(-5575 4250);
WIRE 16 -1 (-5575 4350)(-5575 4250);
WIRE 16 -1 (-5275 4250)(-5575 4250);
WIRE 16 -1 (-5275 4350)(-5275 4250);
WIRE 16 -1 (-4950 4250)(-5275 4250);
WIRE 16 -1 (-4950 4350)(-4950 4250);
WIRE 16 -1 (-4625 4250)(-4950 4250);
WIRE 16 -1 (-4625 4325)(-4625 4250);
WIRE 16 -1 (-4325 4250)(-4625 4250);
WIRE 16 -1 (-4325 4325)(-4325 4250);
WIRE 16 -1 (-4325 4175)(-4325 4250);
WIRE 16 -1 (-7725 4350)(-7725 4250);
WIRE 16 -1 (-7725 4250)(-7375 4250);
WIRE 16 -1 (-7375 4350)(-7375 4250);
WIRE 16 -1 (-7375 4250)(-7050 4250);
WIRE 16 -1 (-7050 4350)(-7050 4250);
WIRE 16 -1 (-7050 4250)(-6675 4250);
WIRE 16 -1 (-6675 4350)(-6675 4250);
WIRE 16 -1 (-6675 4250)(-6350 4250);
WIRE 16 -1 (-6350 4350)(-6350 4250);
WIRE 16 -1 (-6350 4175)(-6350 4250);
WIRE 16 -1 (-6350 4625)(-6350 4550);
WIRE 16 -1 (-6350 4625)(-6675 4625);
WIRE 16 -1 (-6675 4550)(-6675 4625);
WIRE 16 -1 (-7050 4625)(-6675 4625);
WIRE 16 -1 (-7050 4550)(-7050 4625);
WIRE 16 -1 (-7375 4625)(-7050 4625);
WIRE 16 -1 (-7375 4550)(-7375 4625);
WIRE 16 -1 (-7725 4625)(-7375 4625);
WIRE 16 -1 (-7725 4625)(-7725 4675);
WIRE 16 -1 (-7725 4625)(-7725 4550);
WIRE 16 -1 (-5875 3675)(-5875 3575);
WIRE 16 -1 (-5875 3575)(-5550 3575);
WIRE 16 -1 (-5550 3675)(-5550 3575);
WIRE 16 -1 (-5225 3575)(-5550 3575);
WIRE 16 -1 (-5225 3675)(-5225 3575);
WIRE 16 -1 (-4900 3575)(-5225 3575);
WIRE 16 -1 (-4900 3675)(-4900 3575);
WIRE 16 -1 (-4625 3575)(-4900 3575);
WIRE 16 -1 (-4625 3650)(-4625 3575);
WIRE 16 -1 (-4625 3575)(-4325 3575);
WIRE 16 -1 (-4325 3650)(-4325 3575);
WIRE 16 -1 (-4325 3500)(-4325 3575);
WIRE 16 -1 (-5850 3050)(-5850 2950);
WIRE 16 -1 (-5850 2950)(-5500 2950);
WIRE 16 -1 (-5500 3050)(-5500 2950);
WIRE 16 -1 (-5200 2950)(-5500 2950);
WIRE 16 -1 (-5200 3050)(-5200 2950);
WIRE 16 -1 (-4875 2950)(-5200 2950);
WIRE 16 -1 (-4875 3025)(-4875 2950);
WIRE 16 -1 (-4600 2950)(-4875 2950);
WIRE 16 -1 (-4600 3050)(-4600 2950);
WIRE 16 -1 (-4600 2950)(-4325 2950);
WIRE 16 -1 (-4325 3050)(-4325 2950);
WIRE 16 -1 (-4325 2900)(-4325 2950);
WIRE 16 -1 (-5975 2100)(-5975 2000);
WIRE 16 -1 (-5975 2000)(-5700 2000);
WIRE 16 -1 (-5700 2100)(-5700 2000);
WIRE 16 -1 (-5425 2000)(-5700 2000);
WIRE 16 -1 (-5425 2100)(-5425 2000);
WIRE 16 -1 (-5150 2000)(-5425 2000);
WIRE 16 -1 (-5150 2100)(-5150 2000);
WIRE 16 -1 (-5150 1875)(-5150 2000);
WIRE 16 -1 (-5975 1450)(-5975 1350);
WIRE 16 -1 (-5975 1350)(-5625 1350);
WIRE 16 -1 (-5625 1450)(-5625 1350);
WIRE 16 -1 (-5625 1350)(-5300 1350);
WIRE 16 -1 (-5300 1450)(-5300 1350);
WIRE 16 -1 (-5300 1275)(-5300 1350);
WIRE 16 -1 (-5950 775)(-5950 675);
WIRE 16 -1 (-5950 675)(-5600 675);
WIRE 16 -1 (-5600 775)(-5600 675);
WIRE 16 -1 (-5600 675)(-5275 675);
WIRE 16 -1 (-5275 775)(-5275 675);
WIRE 16 -1 (-5275 625)(-5275 675);
WIRE 16 2175 (-7925 4850)(-100 4850);
WIRE 16 2175 (-7925 2675)(-7925 4850);
WIRE 16 2175 (-100 4850)(-100 2675);
WIRE 16 2175 (-100 2675)(-7925 2675);
WIRE 16 2175 (-125 2625)(-125 500);
WIRE 16 2175 (-7900 2625)(-125 2625);
WIRE 16 2175 (-125 500)(-7900 500);
WIRE 16 2175 (-7900 500)(-7900 2625);
DOT 1 (-4875 3325);
DOT 1 (-2100 725);
DOT 1 (-2375 725);
DOT 1 (-2375 1100);
DOT 1 (-1225 1950);
DOT 1 (-1225 2325);
DOT 1 (-975 1950);
DOT 1 (-975 2325);
DOT 1 (-500 1950);
DOT 1 (-700 2325);
DOT 1 (-700 1950);
DOT 1 (-1450 1950);
DOT 1 (-1450 2325);
DOT 1 (-1750 2325);
DOT 1 (-4525 1950);
DOT 1 (-4275 1950);
DOT 1 (-4775 2325);
DOT 1 (-4525 2325);
DOT 1 (-4275 2325);
DOT 1 (-4000 1950);
DOT 1 (-3725 1950);
DOT 1 (-3425 1950);
DOT 1 (-3175 1950);
DOT 1 (-2925 1950);
DOT 1 (-2625 1950);
DOT 1 (-2325 1950);
DOT 1 (-4000 2325);
DOT 1 (-3725 2325);
DOT 1 (-3425 2325);
DOT 1 (-3175 2325);
DOT 1 (-2925 2325);
DOT 1 (-2625 2325);
DOT 1 (-2325 2325);
DOT 1 (-2025 1950);
DOT 1 (-1750 1950);
DOT 1 (-2025 2325);
DOT 1 (-5150 2000);
DOT 1 (-5425 2000);
DOT 1 (-5425 2375);
DOT 1 (-5700 2000);
DOT 1 (-5700 2375);
DOT 1 (-5625 1725);
DOT 1 (-4125 750);
DOT 1 (-4125 1125);
DOT 1 (-3800 750);
DOT 1 (-2950 725);
DOT 1 (-2950 1100);
DOT 1 (-2625 725);
DOT 1 (-2625 1100);
DOT 1 (-6950 2950);
DOT 1 (-725 3500);
DOT 1 (-950 3500);
DOT 1 (-1200 3500);
DOT 1 (-1700 3500);
DOT 1 (-1450 3500);
DOT 1 (-1600 4625);
DOT 1 (-950 3900);
DOT 1 (-1200 3900);
DOT 1 (-1450 3900);
DOT 1 (-1700 3900);
DOT 1 (-1950 3900);
DOT 1 (-2450 4250);
DOT 1 (-2975 4250);
DOT 1 (-1275 4250);
DOT 1 (-2750 3925);
DOT 1 (-3750 4625);
DOT 1 (-2750 2850);
DOT 1 (-3925 3250);
DOT 1 (-3525 2850);
DOT 1 (-3150 2850);
DOT 1 (-3525 3250);
DOT 1 (-3150 3250);
DOT 1 (-3975 3925);
DOT 1 (-3675 3550);
DOT 1 (-3675 3925);
DOT 1 (-3350 3550);
DOT 1 (-3350 3925);
DOT 1 (-3050 3550);
DOT 1 (-3050 3925);
DOT 1 (-2750 3550);
DOT 1 (-2450 3550);
DOT 1 (-4325 4250);
DOT 1 (-4625 4250);
DOT 1 (-4625 4625);
DOT 1 (-4950 4250);
DOT 1 (-4950 4625);
DOT 1 (-5275 4250);
DOT 1 (-5275 4625);
DOT 1 (-6950 3325);
DOT 1 (-6350 4250);
DOT 1 (-7050 4625);
DOT 1 (-5575 4625);
DOT 1 (-5550 3575);
DOT 1 (-6600 3325);
DOT 1 (-6650 3950);
DOT 1 (-4325 2950);
DOT 1 (-4325 3575);
DOT 1 (-5975 2375);
DOT 1 (-1875 4625);
DOT 1 (-1600 4250);
DOT 1 (-6675 4625);
DOT 1 (-4625 3950);
DOT 1 (-7050 2000);
DOT 1 (-5875 3950);
DOT 1 (-6675 4250);
DOT 1 (-7050 4250);
DOT 1 (-7375 4250);
DOT 1 (-7375 4625);
DOT 1 (-7725 4625);
DOT 1 (-5600 1050);
DOT 1 (-5275 675);
DOT 1 (-5600 675);
DOT 1 (-6300 3575);
DOT 1 (-6650 3575);
DOT 1 (-7000 3950);
DOT 1 (-7000 3575);
DOT 1 (-6250 2950);
DOT 1 (-6600 2950);
DOT 1 (-7050 2375);
DOT 1 (-7325 3950);
DOT 1 (-7325 3575);
DOT 1 (-7275 3325);
DOT 1 (-7625 3325);
DOT 1 (-7675 3950);
DOT 1 (-7275 2950);
DOT 1 (-7375 2375);
DOT 1 (-7725 2375);
DOT 1 (-6350 1350);
DOT 1 (-6700 2000);
DOT 1 (-6700 1725);
DOT 1 (-7050 1075);
DOT 1 (-6350 700);
DOT 1 (-7050 700);
DOT 1 (-7375 2000);
DOT 1 (-7375 1350);
DOT 1 (-7375 1075);
DOT 1 (-7725 1075);
DOT 1 (-7375 700);
DOT 1 (-7725 1725);
DOT 1 (-5900 4625);
DOT 1 (-5575 4250);
DOT 1 (-5550 3950);
DOT 1 (-5225 3950);
DOT 1 (-5225 3575);
DOT 1 (-4900 3950);
DOT 1 (-4625 3575);
DOT 1 (-5850 3325);
DOT 1 (-5500 3325);
DOT 1 (-5200 2950);
DOT 1 (-4875 2950);
DOT 1 (-4600 3325);
DOT 1 (-4600 2950);
DOT 1 (-4900 3575);
DOT 1 (-7050 1725);
DOT 1 (-7375 1725);
DOT 1 (-6700 1075);
DOT 1 (-6700 2375);
DOT 1 (-7050 1350);
DOT 1 (-6700 1350);
DOT 1 (-6700 700);
DOT 1 (-5975 1725);
DOT 1 (-6350 2000);
DOT 1 (-5950 1050);
DOT 1 (-5300 1350);
DOT 1 (-5200 3325);
DOT 1 (-5500 2950);
DOT 1 (-4000 4625);
DOT 1 (-3750 4250);
DOT 1 (-3500 4625);
DOT 1 (-3500 4250);
DOT 1 (-3250 4625);
DOT 1 (-3250 4250);
DOT 1 (-2975 4625);
DOT 1 (-2725 4625);
DOT 1 (-2725 4250);
DOT 1 (-2450 4625);
DOT 1 (-2175 4625);
DOT 1 (-1275 4625);
DOT 1 (-975 4625);
DOT 1 (-975 4250);
DOT 1 (-725 4250);
DOT 1 (-2175 4250);
DOT 1 (-1875 4250);
DOT 1 (-3300 1100);
DOT 1 (-5625 1350);
DOT 1 (-4475 1125);
FORCENOTE
FULL CAP CONFIG FOR -P SUPPORT.
(-1215 640) 0;
DISPLAY LEFT (-1215 640);
PAINT PURPLE (-1215 640);
FORCENOTE
FULL CAP CONFIG FOR -P SUPPORT.
(-1240 2765) 0;
DISPLAY LEFT (-1240 2765);
PAINT PURPLE (-1240 2765);
FORCENOTE
PVMCP: 22UF, 603, 19X
(-2515 4790) 0;
DISPLAY LEFT (-2515 4790);
PAINT PURPLE (-2515 4790);
FORCENOTE
(DEBUG ONLY)
(-2464 4707) 0;
DISPLAY LEFT (-2464 4707);
DISPLAY 1.021277 (-2464 4707);
PAINT PURPLE (-2464 4707);
FORCENOTE
PVCCIO: 47UF/805/3X, 22UF/603/2X
(-3140 1140) 0;
DISPLAY LEFT (-3140 1140);
PAINT PURPLE (-3140 1140);
FORCENOTE
PVMCP: 47UF, 805, 17X
(-3540 2515) 0;
DISPLAY LEFT (-3540 2515);
PAINT PURPLE (-3540 2515);
FORCENOTE
(DEBUG ONLY)
(-3380 2429) 0;
DISPLAY LEFT (-3380 2429);
DISPLAY 1.021277 (-3380 2429);
PAINT PURPLE (-3380 2429);
FORCENOTE
PVCCIO: 22UF, 603, 6X
(-3465 3990) 0;
DISPLAY LEFT (-3465 3990);
PAINT PURPLE (-3465 3990);
FORCENOTE
PVCCIN: 22UF/603/33X
(-7115 4715) 0;
DISPLAY LEFT (-7115 4715);
PAINT PURPLE (-7115 4715);
FORCENOTE
PVCCIN: 47UF, 805, 25X
(-7140 2465) 0;
DISPLAY LEFT (-7140 2465);
PAINT PURPLE (-7140 2465);
FORCENOTE
ROOM = PVCCIN_CPU1_DECAP_VR
(-7890 190) 0;
DISPLAY LEFT (-7890 190);
DISPLAY 2.446809 (-7890 190);
PAINT PURPLE (-7890 190);
QUIT
